FILE_TYPE = MACRO_DRAWING;
SET COLOR_WIRE YELLOW;
SET COLOR_PROP MONO;
SET COLOR_DOT WHITE;
SET COLOR_ARC YELLOW;
SET COLOR_BODY GREEN;
SET COLOR_NOTE MONO;
SET PROP_DISPLAY VALUE;
SET PAGE_NUMBER P173;
FORCEADD GND..1
(-1150 1425);
FORCEPROP 3 LASTPIN (-1150 1475) SIG_NAME GND\g
J 0
(-1140 1485);
DISPLAY 0.659574 (-1140 1485);
PAINT MONO (-1140 1485);
DISPLAY INVISIBLE (-1140 1485);
FORCEPROP 1 LAST VOLTAGE 0.0V
J 0
(-1195 1382);
DISPLAY 0.340426 (-1195 1382);
PAINT SKYBLUE (-1195 1382);
DISPLAY INVISIBLE (-1195 1382);
FORCEPROP 1 LAST HDL_POWER GND
J 0
(-1150 1575);
DISPLAY 1.170213 (-1150 1575);
PAINT GREEN (-1150 1575);
DISPLAY INVISIBLE (-1150 1575);
FORCEPROP 2 LAST ROOM ST_SATA
J 0
(-1125 1500);
DISPLAY 1.361702 (-1125 1500);
PAINT ORANGE (-1125 1500);
DISPLAY INVISIBLE (-1125 1500);
FORCEPROP 2 LAST BOM_COST ST_SATA
J 0
(-1125 1500);
DISPLAY 1.361702 (-1125 1500);
PAINT ORANGE (-1125 1500);
DISPLAY INVISIBLE (-1125 1500);
FORCEPROP 1 LAST SIZE 1B
J 0
(-1075 1375);
DISPLAY 1.170213 (-1075 1375);
PAINT AQUA (-1075 1375);
DISPLAY INVISIBLE (-1075 1375);
FORCEPROP 2 LAST CDS_LIB mstr_symbols
J 0
(-1150 1425);
PAINT ORANGE (-1150 1425);
DISPLAY INVISIBLE (-1150 1425);
FORCEPROP 1 LAST BODY_TYPE PLUMBING
J 0
(-1195 1382);
DISPLAY 0.340426 (-1195 1382);
PAINT GREEN (-1195 1382);
DISPLAY INVISIBLE (-1195 1382);
FORCEPROP 1 LAST PATH I103
J 0
(-1075 1425);
DISPLAY 0.872340 (-1075 1425);
PAINT AQUA (-1075 1425);
DISPLAY INVISIBLE (-1075 1425);
FORCEADD GND..1
(-2925 1450);
FORCEPROP 3 LASTPIN (-2925 1500) SIG_NAME GND\g
J 0
(-2915 1510);
DISPLAY 0.659574 (-2915 1510);
PAINT MONO (-2915 1510);
DISPLAY INVISIBLE (-2915 1510);
FORCEPROP 1 LAST VOLTAGE 0.0V
J 0
(-2970 1407);
DISPLAY 0.340426 (-2970 1407);
PAINT SKYBLUE (-2970 1407);
DISPLAY INVISIBLE (-2970 1407);
FORCEPROP 1 LAST HDL_POWER GND
J 0
(-2925 1600);
DISPLAY 1.170213 (-2925 1600);
PAINT GREEN (-2925 1600);
DISPLAY INVISIBLE (-2925 1600);
FORCEPROP 2 LAST ROOM ST_SATA
J 0
(-2900 1525);
DISPLAY 1.361702 (-2900 1525);
PAINT ORANGE (-2900 1525);
DISPLAY INVISIBLE (-2900 1525);
FORCEPROP 1 LAST SIZE 1B
J 0
(-2850 1400);
DISPLAY 1.170213 (-2850 1400);
PAINT AQUA (-2850 1400);
DISPLAY INVISIBLE (-2850 1400);
FORCEPROP 2 LAST BOM_COST ST_SATA
J 0
(-2900 1525);
DISPLAY 1.361702 (-2900 1525);
PAINT ORANGE (-2900 1525);
DISPLAY INVISIBLE (-2900 1525);
FORCEPROP 2 LAST CDS_LIB mstr_symbols
J 0
(-2925 1450);
PAINT ORANGE (-2925 1450);
DISPLAY INVISIBLE (-2925 1450);
FORCEPROP 1 LAST BODY_TYPE PLUMBING
J 0
(-2970 1407);
DISPLAY 0.340426 (-2970 1407);
PAINT GREEN (-2970 1407);
DISPLAY INVISIBLE (-2970 1407);
FORCEPROP 1 LAST PATH I162
J 0
(-2850 1450);
DISPLAY 0.872340 (-2850 1450);
PAINT AQUA (-2850 1450);
DISPLAY INVISIBLE (-2850 1450);
FORCEADD CONN72_G97614002_A..1
(-2025 3100);
FORCEPROP 1 LAST LOCATION J8A1
J 0
(-2675 4700);
DISPLAY 0.617021 (-2675 4700);
PAINT AQUA (-2675 4700);
FORCEPROP 1 LAST PART_NUMBER G97614-002
J 0
(-2675 1425);
DISPLAY 0.617021 (-2675 1425);
PAINT BLUE (-2675 1425);
FORCEPROP 1 LAST MATERIAL CONN
J 0
(-2675 4750);
DISPLAY 0.617021 (-2675 4750);
PAINT SKYBLUE (-2675 4750);
FORCEPROP 2 LASTPIN (-1325 2650) $PN 2C4
J 0
(-1315 2660);
DISPLAY 0.617021 (-1315 2660);
PAINT ORANGE (-1315 2660);
FORCEPROP 2 LASTPIN (-1325 2600) $PN 2C5
J 0
(-1315 2610);
DISPLAY 0.617021 (-1315 2610);
PAINT ORANGE (-1315 2610);
FORCEPROP 2 LASTPIN (-1325 1650) $PN 2D9
J 0
(-1315 1660);
DISPLAY 0.617021 (-1315 1660);
PAINT ORANGE (-1315 1660);
FORCEPROP 2 LASTPIN (-1325 1900) $PN 2D6
J 0
(-1315 1910);
DISPLAY 0.617021 (-1315 1910);
PAINT ORANGE (-1315 1910);
FORCEPROP 2 LASTPIN (-1325 2150) $PN 2D3
J 0
(-1315 2160);
DISPLAY 0.617021 (-1315 2160);
PAINT ORANGE (-1315 2160);
FORCEPROP 2 LASTPIN (-1325 2500) $PN 2C9
J 0
(-1315 2510);
DISPLAY 0.617021 (-1315 2510);
PAINT ORANGE (-1315 2510);
FORCEPROP 2 LASTPIN (-1325 2750) $PN 2C6
J 0
(-1315 2760);
DISPLAY 0.617021 (-1315 2760);
PAINT ORANGE (-1315 2760);
FORCEPROP 2 LASTPIN (-1325 3000) $PN 2C3
J 0
(-1315 3010);
DISPLAY 0.617021 (-1315 3010);
PAINT ORANGE (-1315 3010);
FORCEPROP 2 LASTPIN (-2725 1650) $PN 2B9
J 2
(-2735 1660);
DISPLAY 0.617021 (-2735 1660);
PAINT ORANGE (-2735 1660);
FORCEPROP 2 LASTPIN (-2725 1900) $PN 2B6
J 2
(-2735 1910);
DISPLAY 0.617021 (-2735 1910);
PAINT ORANGE (-2735 1910);
FORCEPROP 2 LASTPIN (-2725 2150) $PN 2B3
J 2
(-2735 2160);
DISPLAY 0.617021 (-2735 2160);
PAINT ORANGE (-2735 2160);
FORCEPROP 2 LASTPIN (-2725 2750) $PN 2A9
J 2
(-2735 2760);
DISPLAY 0.617021 (-2735 2760);
PAINT ORANGE (-2735 2760);
FORCEPROP 2 LASTPIN (-2725 2500) $PN 2A6
J 2
(-2735 2510);
DISPLAY 0.617021 (-2735 2510);
PAINT ORANGE (-2735 2510);
FORCEPROP 2 LASTPIN (-2725 3000) $PN 2A3
J 2
(-2735 3010);
DISPLAY 0.617021 (-2735 3010);
PAINT ORANGE (-2735 3010);
FORCEPROP 2 LASTPIN (-1325 3150) $PN 1D9
J 0
(-1315 3160);
DISPLAY 0.617021 (-1315 3160);
PAINT ORANGE (-1315 3160);
FORCEPROP 2 LASTPIN (-1325 3400) $PN 1D6
J 0
(-1315 3410);
DISPLAY 0.617021 (-1315 3410);
PAINT ORANGE (-1315 3410);
FORCEPROP 2 LASTPIN (-1325 3650) $PN 1D3
J 0
(-1315 3660);
DISPLAY 0.617021 (-1315 3660);
PAINT ORANGE (-1315 3660);
FORCEPROP 2 LASTPIN (-1325 4000) $PN 1C9
J 0
(-1315 4010);
DISPLAY 0.617021 (-1315 4010);
PAINT ORANGE (-1315 4010);
FORCEPROP 2 LASTPIN (-1325 4250) $PN 1C6
J 0
(-1315 4260);
DISPLAY 0.617021 (-1315 4260);
PAINT ORANGE (-1315 4260);
FORCEPROP 2 LASTPIN (-1325 4500) $PN 1C3
J 0
(-1315 4510);
DISPLAY 0.617021 (-1315 4510);
PAINT ORANGE (-1315 4510);
FORCEPROP 2 LASTPIN (-2725 3150) $PN 1B9
J 2
(-2735 3160);
DISPLAY 0.617021 (-2735 3160);
PAINT ORANGE (-2735 3160);
FORCEPROP 2 LASTPIN (-2725 3400) $PN 1B6
J 2
(-2735 3410);
DISPLAY 0.617021 (-2735 3410);
PAINT ORANGE (-2735 3410);
FORCEPROP 2 LASTPIN (-2725 3650) $PN 1B3
J 2
(-2735 3660);
DISPLAY 0.617021 (-2735 3660);
PAINT ORANGE (-2735 3660);
FORCEPROP 2 LASTPIN (-2725 4000) $PN 1A9
J 2
(-2735 4010);
DISPLAY 0.617021 (-2735 4010);
PAINT ORANGE (-2735 4010);
FORCEPROP 2 LASTPIN (-2725 4250) $PN 1A6
J 2
(-2735 4260);
DISPLAY 0.617021 (-2735 4260);
PAINT ORANGE (-2735 4260);
FORCEPROP 2 LASTPIN (-2725 4500) $PN 1A3
J 2
(-2735 4510);
DISPLAY 0.617021 (-2735 4510);
PAINT ORANGE (-2735 4510);
FORCEPROP 2 LASTPIN (-2725 4350) $PN 1B5
J 2
(-2735 4360);
DISPLAY 0.617021 (-2735 4360);
PAINT ORANGE (-2735 4360);
FORCEPROP 2 LASTPIN (-2725 4400) $PN 1B4
J 2
(-2735 4410);
DISPLAY 0.617021 (-2735 4410);
PAINT ORANGE (-2735 4410);
FORCEPROP 2 LASTPIN (-2725 4100) $PN 1A5
J 2
(-2735 4110);
DISPLAY 0.617021 (-2735 4110);
PAINT ORANGE (-2735 4110);
FORCEPROP 2 LASTPIN (-2725 4150) $PN 1A4
J 2
(-2735 4160);
DISPLAY 0.617021 (-2735 4160);
PAINT ORANGE (-2735 4160);
FORCEPROP 2 LASTPIN (-2725 3500) $PN 1B8
J 2
(-2735 3510);
DISPLAY 0.617021 (-2735 3510);
PAINT ORANGE (-2735 3510);
FORCEPROP 2 LASTPIN (-2725 3550) $PN 1B7
J 2
(-2735 3560);
DISPLAY 0.617021 (-2735 3560);
PAINT ORANGE (-2735 3560);
FORCEPROP 2 LASTPIN (-2725 3250) $PN 1A8
J 2
(-2735 3260);
DISPLAY 0.617021 (-2735 3260);
PAINT ORANGE (-2735 3260);
FORCEPROP 2 LASTPIN (-2725 3300) $PN 1A7
J 2
(-2735 3310);
DISPLAY 0.617021 (-2735 3310);
PAINT ORANGE (-2735 3310);
FORCEPROP 2 LASTPIN (-2725 2850) $PN 2B5
J 2
(-2735 2860);
DISPLAY 0.617021 (-2735 2860);
PAINT ORANGE (-2735 2860);
FORCEPROP 2 LASTPIN (-2725 2900) $PN 2B4
J 2
(-2735 2910);
DISPLAY 0.617021 (-2735 2910);
PAINT ORANGE (-2735 2910);
FORCEPROP 2 LASTPIN (-2725 2600) $PN 2A5
J 2
(-2735 2610);
DISPLAY 0.617021 (-2735 2610);
PAINT ORANGE (-2735 2610);
FORCEPROP 2 LASTPIN (-2725 2650) $PN 2A4
J 2
(-2735 2660);
DISPLAY 0.617021 (-2735 2660);
PAINT ORANGE (-2735 2660);
FORCEPROP 2 LASTPIN (-2725 2000) $PN 2B8
J 2
(-2735 2010);
DISPLAY 0.617021 (-2735 2010);
PAINT ORANGE (-2735 2010);
FORCEPROP 2 LASTPIN (-2725 2050) $PN 2B7
J 2
(-2735 2060);
DISPLAY 0.617021 (-2735 2060);
PAINT ORANGE (-2735 2060);
FORCEPROP 2 LASTPIN (-2725 1750) $PN 2A8
J 2
(-2735 1760);
DISPLAY 0.617021 (-2735 1760);
PAINT ORANGE (-2735 1760);
FORCEPROP 2 LASTPIN (-1325 3900) $PN 1A2
J 0
(-1315 3910);
DISPLAY 0.617021 (-1315 3910);
PAINT ORANGE (-1315 3910);
FORCEPROP 2 LASTPIN (-1325 3850) $PN 1B2
J 0
(-1315 3860);
DISPLAY 0.617021 (-1315 3860);
PAINT ORANGE (-1315 3860);
FORCEPROP 2 LASTPIN (-1325 3800) $PN 1C2
J 0
(-1315 3810);
DISPLAY 0.617021 (-1315 3810);
PAINT ORANGE (-1315 3810);
FORCEPROP 2 LASTPIN (-2725 3850) $PN 1B1
J 2
(-2735 3860);
DISPLAY 0.617021 (-2735 3860);
PAINT ORANGE (-2735 3860);
FORCEPROP 2 LASTPIN (-2725 3800) $PN 1C1
J 2
(-2735 3810);
DISPLAY 0.617021 (-2735 3810);
PAINT ORANGE (-2735 3810);
FORCEPROP 2 LASTPIN (-2725 3750) $PN 1D1
J 2
(-2735 3760);
DISPLAY 0.617021 (-2735 3760);
PAINT ORANGE (-2735 3760);
FORCEPROP 2 LASTPIN (-1325 3750) $PN 1D2
J 0
(-1315 3760);
DISPLAY 0.617021 (-1315 3760);
PAINT ORANGE (-1315 3760);
FORCEPROP 2 LASTPIN (-2725 3900) $PN 1A1
J 2
(-2735 3910);
DISPLAY 0.617021 (-2735 3910);
PAINT ORANGE (-2735 3910);
FORCEPROP 2 LASTPIN (-1325 2400) $PN 2A2
J 0
(-1315 2410);
DISPLAY 0.617021 (-1315 2410);
PAINT ORANGE (-1315 2410);
FORCEPROP 2 LASTPIN (-1325 2350) $PN 2B2
J 0
(-1315 2360);
DISPLAY 0.617021 (-1315 2360);
PAINT ORANGE (-1315 2360);
FORCEPROP 2 LASTPIN (-1325 2300) $PN 2C2
J 0
(-1315 2310);
DISPLAY 0.617021 (-1315 2310);
PAINT ORANGE (-1315 2310);
FORCEPROP 2 LASTPIN (-2725 2350) $PN 2B1
J 2
(-2735 2360);
DISPLAY 0.617021 (-2735 2360);
PAINT ORANGE (-2735 2360);
FORCEPROP 2 LASTPIN (-2725 2300) $PN 2C1
J 2
(-2735 2310);
DISPLAY 0.617021 (-2735 2310);
PAINT ORANGE (-2735 2310);
FORCEPROP 2 LASTPIN (-2725 2250) $PN 2D1
J 2
(-2735 2260);
DISPLAY 0.617021 (-2735 2260);
PAINT ORANGE (-2735 2260);
FORCEPROP 2 LASTPIN (-1325 2250) $PN 2D2
J 0
(-1315 2260);
DISPLAY 0.617021 (-1315 2260);
PAINT ORANGE (-1315 2260);
FORCEPROP 2 LASTPIN (-2725 2400) $PN 2A1
J 2
(-2735 2410);
DISPLAY 0.617021 (-2735 2410);
PAINT ORANGE (-2735 2410);
FORCEPROP 2 LASTPIN (-1325 4350) $PN 1D5
J 0
(-1315 4360);
DISPLAY 0.617021 (-1315 4360);
PAINT ORANGE (-1315 4360);
FORCEPROP 2 LASTPIN (-1325 4400) $PN 1D4
J 0
(-1315 4410);
DISPLAY 0.617021 (-1315 4410);
PAINT ORANGE (-1315 4410);
FORCEPROP 2 LASTPIN (-1325 4100) $PN 1C5
J 0
(-1315 4110);
DISPLAY 0.617021 (-1315 4110);
PAINT ORANGE (-1315 4110);
FORCEPROP 2 LASTPIN (-1325 4150) $PN 1C4
J 0
(-1315 4160);
DISPLAY 0.617021 (-1315 4160);
PAINT ORANGE (-1315 4160);
FORCEPROP 2 LASTPIN (-1325 3500) $PN 1D8
J 0
(-1315 3510);
DISPLAY 0.617021 (-1315 3510);
PAINT ORANGE (-1315 3510);
FORCEPROP 2 LASTPIN (-1325 3550) $PN 1D7
J 0
(-1315 3560);
DISPLAY 0.617021 (-1315 3560);
PAINT ORANGE (-1315 3560);
FORCEPROP 2 LASTPIN (-1325 3250) $PN 1C8
J 0
(-1315 3260);
DISPLAY 0.617021 (-1315 3260);
PAINT ORANGE (-1315 3260);
FORCEPROP 2 LASTPIN (-1325 3300) $PN 1C7
J 0
(-1315 3310);
DISPLAY 0.617021 (-1315 3310);
PAINT ORANGE (-1315 3310);
FORCEPROP 2 LASTPIN (-1325 2850) $PN 2D5
J 0
(-1315 2860);
DISPLAY 0.617021 (-1315 2860);
PAINT ORANGE (-1315 2860);
FORCEPROP 2 LASTPIN (-1325 2900) $PN 2D4
J 0
(-1315 2910);
DISPLAY 0.617021 (-1315 2910);
PAINT ORANGE (-1315 2910);
FORCEPROP 2 LASTPIN (-1325 2000) $PN 2D8
J 0
(-1315 2010);
DISPLAY 0.617021 (-1315 2010);
PAINT ORANGE (-1315 2010);
FORCEPROP 2 LASTPIN (-1325 2050) $PN 2D7
J 0
(-1315 2060);
DISPLAY 0.617021 (-1315 2060);
PAINT ORANGE (-1315 2060);
FORCEPROP 2 LASTPIN (-1325 1750) $PN 2C8
J 0
(-1315 1760);
DISPLAY 0.617021 (-1315 1760);
PAINT ORANGE (-1315 1760);
FORCEPROP 2 LASTPIN (-1325 1800) $PN 2C7
J 0
(-1315 1810);
DISPLAY 0.617021 (-1315 1810);
PAINT ORANGE (-1315 1810);
FORCEPROP 2 LASTPIN (-2725 1800) $PN 2A7
J 2
(-2735 1810);
DISPLAY 0.617021 (-2735 1810);
PAINT ORANGE (-2735 1810);
FORCEPROP 1 LAST PACK_TYPE CP
J 0
(-2675 5500);
PAINT SKYBLUE (-2675 5500);
DISPLAY INVISIBLE (-2675 5500);
FORCEPROP 2 LAST ROOM ST_SATA
J 0
(-2625 4750);
DISPLAY 1.361702 (-2625 4750);
PAINT ORANGE (-2625 4750);
DISPLAY INVISIBLE (-2625 4750);
FORCEPROP 1 LAST PATH I163
J 0
(-2025 4700);
PAINT GREEN (-2025 4700);
DISPLAY INVISIBLE (-2025 4700);
FORCEPROP 2 LAST CDS_LOCATION J8A1
J 0
(-2675 4700);
DISPLAY 0.617021 (-2675 4700);
PAINT AQUA (-2675 4700);
DISPLAY INVISIBLE (-2675 4700);
FORCEPROP 2 LAST SEC 1
J 0
(-2025 5450);
DISPLAY 0.680851 (-2025 5450);
PAINT MONO (-2025 5450);
DISPLAY INVISIBLE (-2025 5450);
FORCEPROP 2 LAST SEC_TYPE CP
J 0
(-2025 5450);
DISPLAY 1.021277 (-2025 5450);
PAINT ORANGE (-2025 5450);
DISPLAY INVISIBLE (-2025 5450);
FORCEPROP 2 LAST CDS_LIB mstr_conn
J 0
(-2025 3800);
PAINT ORANGE (-2025 3800);
DISPLAY INVISIBLE (-2025 3800);
FORCEPROP 2 LAST BOM_COST ST_SATA
J 0
(-2625 4750);
DISPLAY 1.361702 (-2625 4750);
PAINT ORANGE (-2625 4750);
DISPLAY INVISIBLE (-2625 4750);
FORCEADD CAP_A..2
(-4900 3550);
FORCEPROP 1 LAST LOCATION C2L13
J 1
(-4900 3650);
DISPLAY 0.617021 (-4900 3650);
PAINT AQUA (-4900 3650);
FORCEPROP 1 LAST PART_NUMBER A36096-045
J 1
(-4900 3600);
DISPLAY 0.617021 (-4900 3600);
PAINT BLUE (-4900 3600);
FORCEPROP 1 LAST VALUE 0.01UF
J 2
(-4900 3450);
DISPLAY 0.617021 (-4900 3450);
PAINT SKYBLUE (-4900 3450);
FORCEPROP 1 LAST TOLERANCE 10%
J 2
(-4900 3400);
DISPLAY 0.617021 (-4900 3400);
PAINT SKYBLUE (-4900 3400);
FORCEPROP 1 LAST PACK_TYPE 0402V
J 1
(-4900 3350);
DISPLAY 0.617021 (-4900 3350);
PAINT SKYBLUE (-4900 3350);
FORCEPROP 1 LAST VOLTAGE 25V
J 0
(-4900 3450);
DISPLAY 0.617021 (-4900 3450);
PAINT SKYBLUE (-4900 3450);
FORCEPROP 1 LAST MATERIAL X7R
J 0
(-4900 3400);
DISPLAY 0.617021 (-4900 3400);
PAINT SKYBLUE (-4900 3400);
FORCEPROP 1 LASTPIN (-5000 3550) $PN 1
J 0
(-5010 3565);
DISPLAY 0.617021 (-5010 3565);
PAINT ORANGE (-5010 3565);
FORCEPROP 1 LASTPIN (-4800 3550) $PN 2
J 0
(-4815 3565);
DISPLAY 0.617021 (-4815 3565);
PAINT ORANGE (-4815 3565);
FORCEPROP 2 LAST ROOM ST_SATA
J 0
(-4950 3700);
DISPLAY 1.361702 (-4950 3700);
PAINT ORANGE (-4950 3700);
DISPLAY INVISIBLE (-4950 3700);
FORCEPROP 2 LAST CDS_LOCATION C2L13
J 1
(-4900 3650);
DISPLAY 0.617021 (-4900 3650);
PAINT AQUA (-4900 3650);
DISPLAY INVISIBLE (-4900 3650);
FORCEPROP 2 LAST BOM_COST ST_SATA
J 0
(-4950 3650);
DISPLAY 1.361702 (-4950 3650);
PAINT ORANGE (-4950 3650);
DISPLAY INVISIBLE (-4950 3650);
FORCEPROP 2 LAST CDS_LIB dev_discrete
J 0
(-4900 3550);
PAINT ORANGE (-4900 3550);
DISPLAY INVISIBLE (-4900 3550);
FORCEPROP 2 LAST CDS_SEC 1
J 0
(-4900 3700);
PAINT ORANGE (-4900 3700);
DISPLAY INVISIBLE (-4900 3700);
FORCEPROP 2 LAST SEC_TYPE 0402V
J 0
(-4900 3800);
DISPLAY 1.021277 (-4900 3800);
PAINT ORANGE (-4900 3800);
DISPLAY INVISIBLE (-4900 3800);
FORCEPROP 2 LAST SEC 1
J 0
(-4900 3800);
DISPLAY 0.680851 (-4900 3800);
PAINT MONO (-4900 3800);
DISPLAY INVISIBLE (-4900 3800);
FORCEPROP 1 LAST PATH I165
J 0
(-4900 3750);
DISPLAY 0.978723 (-4900 3750);
PAINT WHITE (-4900 3750);
DISPLAY INVISIBLE (-4900 3750);
FORCEADD CAP_A..2
(-4850 4050);
FORCEPROP 1 LAST LOCATION C2L6
J 1
(-4850 4150);
DISPLAY 0.617021 (-4850 4150);
PAINT AQUA (-4850 4150);
FORCEPROP 1 LAST PART_NUMBER A36096-045
J 1
(-4850 4100);
DISPLAY 0.617021 (-4850 4100);
PAINT BLUE (-4850 4100);
FORCEPROP 1 LAST VALUE 0.01UF
J 2
(-4850 3950);
DISPLAY 0.617021 (-4850 3950);
PAINT SKYBLUE (-4850 3950);
FORCEPROP 1 LAST TOLERANCE 10%
J 2
(-4850 3900);
DISPLAY 0.617021 (-4850 3900);
PAINT SKYBLUE (-4850 3900);
FORCEPROP 1 LAST PACK_TYPE 0402V
J 1
(-4850 3850);
DISPLAY 0.617021 (-4850 3850);
PAINT SKYBLUE (-4850 3850);
FORCEPROP 1 LAST VOLTAGE 25V
J 0
(-4850 3950);
DISPLAY 0.617021 (-4850 3950);
PAINT SKYBLUE (-4850 3950);
FORCEPROP 1 LAST MATERIAL X7R
J 0
(-4850 3900);
DISPLAY 0.617021 (-4850 3900);
PAINT SKYBLUE (-4850 3900);
FORCEPROP 1 LASTPIN (-4750 4050) $PN 2
J 0
(-4765 4065);
DISPLAY 0.617021 (-4765 4065);
PAINT ORANGE (-4765 4065);
FORCEPROP 1 LASTPIN (-4950 4050) $PN 1
J 0
(-4960 4065);
DISPLAY 0.617021 (-4960 4065);
PAINT ORANGE (-4960 4065);
FORCEPROP 2 LAST ROOM ST_SATA
J 0
(-4900 4200);
DISPLAY 1.361702 (-4900 4200);
PAINT ORANGE (-4900 4200);
DISPLAY INVISIBLE (-4900 4200);
FORCEPROP 1 LAST PATH I166
J 0
(-4850 4250);
DISPLAY 0.978723 (-4850 4250);
PAINT WHITE (-4850 4250);
DISPLAY INVISIBLE (-4850 4250);
FORCEPROP 2 LAST SEC 1
J 0
(-4850 4300);
DISPLAY 0.680851 (-4850 4300);
PAINT MONO (-4850 4300);
DISPLAY INVISIBLE (-4850 4300);
FORCEPROP 2 LAST SEC_TYPE 0402V
J 0
(-4850 4300);
DISPLAY 1.021277 (-4850 4300);
PAINT ORANGE (-4850 4300);
DISPLAY INVISIBLE (-4850 4300);
FORCEPROP 2 LAST CDS_SEC 1
J 0
(-4850 4200);
PAINT ORANGE (-4850 4200);
DISPLAY INVISIBLE (-4850 4200);
FORCEPROP 2 LAST CDS_LIB dev_discrete
J 0
(-4850 4050);
PAINT ORANGE (-4850 4050);
DISPLAY INVISIBLE (-4850 4050);
FORCEPROP 2 LAST BOM_COST ST_SATA
J 0
(-4900 4150);
DISPLAY 1.361702 (-4900 4150);
PAINT ORANGE (-4900 4150);
DISPLAY INVISIBLE (-4900 4150);
FORCEPROP 2 LAST CDS_LOCATION C2L6
J 1
(-4850 4150);
DISPLAY 0.617021 (-4850 4150);
PAINT AQUA (-4850 4150);
DISPLAY INVISIBLE (-4850 4150);
FORCEADD OFFPAGE..2
(-4300 5300);
FORCEPROP 2 LAST $XR0 116 
J 0
(-4111 5300);
DISPLAY 0.638298 (-4111 5300);
PAINT MONO (-4111 5300);
FORCEPROP 2 LAST CDS_LIB mstr_standard
J 0
(-4300 5300);
PAINT ORANGE (-4300 5300);
DISPLAY INVISIBLE (-4300 5300);
FORCEPROP 1 LAST OFFPAGE TRUE
J 0
(-3975 5175);
DISPLAY 0.872340 (-3975 5175);
PAINT GREEN (-3975 5175);
DISPLAY INVISIBLE (-3975 5175);
FORCEPROP 1 LAST COMMENT_BODY TRUE
J 0
(-4345 5205);
DISPLAY 0.872340 (-4345 5205);
PAINT GREEN (-4345 5205);
DISPLAY INVISIBLE (-4345 5205);
FORCEPROP 2 LAST PATH I170
J 0
(-4100 5350);
DISPLAY 1.021277 (-4100 5350);
PAINT ORANGE (-4100 5350);
DISPLAY INVISIBLE (-4100 5350);
FORCEADD OFFPAGE..2
(-4300 5150);
FORCEPROP 2 LAST $XR0 116 
J 0
(-4111 5150);
DISPLAY 0.638298 (-4111 5150);
PAINT MONO (-4111 5150);
FORCEPROP 2 LAST CDS_LIB mstr_standard
J 0
(-4300 5150);
PAINT ORANGE (-4300 5150);
DISPLAY INVISIBLE (-4300 5150);
FORCEPROP 1 LAST OFFPAGE TRUE
J 0
(-3975 5025);
DISPLAY 0.872340 (-3975 5025);
PAINT GREEN (-3975 5025);
DISPLAY INVISIBLE (-3975 5025);
FORCEPROP 1 LAST COMMENT_BODY TRUE
J 0
(-4345 5055);
DISPLAY 0.872340 (-4345 5055);
PAINT GREEN (-4345 5055);
DISPLAY INVISIBLE (-4345 5055);
FORCEPROP 2 LAST PATH I171
J 0
(-4100 5200);
DISPLAY 1.021277 (-4100 5200);
PAINT ORANGE (-4100 5200);
DISPLAY INVISIBLE (-4100 5200);
FORCEADD CAP_A..2
(-4575 4550);
FORCEPROP 1 LAST LOCATION C2L19
J 1
(-4575 4650);
DISPLAY 0.617021 (-4575 4650);
PAINT AQUA (-4575 4650);
FORCEPROP 1 LAST PART_NUMBER A36096-045
J 1
(-4575 4600);
DISPLAY 0.617021 (-4575 4600);
PAINT BLUE (-4575 4600);
FORCEPROP 1 LAST VALUE 0.01UF
J 2
(-4575 4450);
DISPLAY 0.617021 (-4575 4450);
PAINT SKYBLUE (-4575 4450);
FORCEPROP 1 LAST TOLERANCE 10%
J 2
(-4575 4400);
DISPLAY 0.617021 (-4575 4400);
PAINT SKYBLUE (-4575 4400);
FORCEPROP 1 LAST PACK_TYPE 0402V
J 1
(-4575 4350);
DISPLAY 0.617021 (-4575 4350);
PAINT SKYBLUE (-4575 4350);
FORCEPROP 1 LAST VOLTAGE 25V
J 0
(-4575 4450);
DISPLAY 0.617021 (-4575 4450);
PAINT SKYBLUE (-4575 4450);
FORCEPROP 1 LAST MATERIAL X7R
J 0
(-4575 4400);
DISPLAY 0.617021 (-4575 4400);
PAINT SKYBLUE (-4575 4400);
FORCEPROP 1 LASTPIN (-4475 4550) $PN 2
J 0
(-4490 4565);
DISPLAY 0.617021 (-4490 4565);
PAINT ORANGE (-4490 4565);
FORCEPROP 1 LASTPIN (-4675 4550) $PN 1
J 0
(-4685 4565);
DISPLAY 0.617021 (-4685 4565);
PAINT ORANGE (-4685 4565);
FORCEPROP 2 LAST ROOM ST_SATA
J 0
(-4625 4700);
DISPLAY 1.361702 (-4625 4700);
PAINT ORANGE (-4625 4700);
DISPLAY INVISIBLE (-4625 4700);
FORCEPROP 2 LAST CDS_LOCATION C2L19
J 1
(-4575 4650);
DISPLAY 0.617021 (-4575 4650);
PAINT AQUA (-4575 4650);
DISPLAY INVISIBLE (-4575 4650);
FORCEPROP 2 LAST BOM_COST ST_SATA
J 0
(-4625 4650);
DISPLAY 1.361702 (-4625 4650);
PAINT ORANGE (-4625 4650);
DISPLAY INVISIBLE (-4625 4650);
FORCEPROP 2 LAST CDS_LIB dev_discrete
J 0
(-4575 4550);
PAINT ORANGE (-4575 4550);
DISPLAY INVISIBLE (-4575 4550);
FORCEPROP 2 LAST CDS_SEC 1
J 0
(-4575 4700);
PAINT ORANGE (-4575 4700);
DISPLAY INVISIBLE (-4575 4700);
FORCEPROP 2 LAST SEC_TYPE 0402V
J 0
(-4575 4800);
DISPLAY 1.021277 (-4575 4800);
PAINT ORANGE (-4575 4800);
DISPLAY INVISIBLE (-4575 4800);
FORCEPROP 2 LAST SEC 1
J 0
(-4575 4800);
DISPLAY 0.680851 (-4575 4800);
PAINT MONO (-4575 4800);
DISPLAY INVISIBLE (-4575 4800);
FORCEPROP 1 LAST PATH I172
J 0
(-4575 4750);
DISPLAY 0.978723 (-4575 4750);
PAINT WHITE (-4575 4750);
DISPLAY INVISIBLE (-4575 4750);
FORCEADD CAP_A..2
(-4575 4200);
FORCEPROP 1 LAST PART_NUMBER A36096-045
J 1
(-4575 4250);
DISPLAY 0.617021 (-4575 4250);
PAINT BLUE (-4575 4250);
FORCEPROP 1 LAST VALUE 0.01UF
J 2
(-4575 4100);
DISPLAY 0.617021 (-4575 4100);
PAINT SKYBLUE (-4575 4100);
FORCEPROP 1 LAST TOLERANCE 10%
J 2
(-4575 4050);
DISPLAY 0.617021 (-4575 4050);
PAINT SKYBLUE (-4575 4050);
FORCEPROP 1 LAST PACK_TYPE 0402V
J 1
(-4575 4000);
DISPLAY 0.617021 (-4575 4000);
PAINT SKYBLUE (-4575 4000);
FORCEPROP 1 LAST VOLTAGE 25V
J 0
(-4575 4100);
DISPLAY 0.617021 (-4575 4100);
PAINT SKYBLUE (-4575 4100);
FORCEPROP 1 LAST MATERIAL X7R
J 0
(-4575 4050);
DISPLAY 0.617021 (-4575 4050);
PAINT SKYBLUE (-4575 4050);
FORCEPROP 1 LASTPIN (-4475 4200) $PN 2
J 0
(-4490 4215);
DISPLAY 0.617021 (-4490 4215);
PAINT ORANGE (-4490 4215);
FORCEPROP 1 LASTPIN (-4675 4200) $PN 1
J 0
(-4685 4215);
DISPLAY 0.617021 (-4685 4215);
PAINT ORANGE (-4685 4215);
FORCEPROP 1 LAST LOCATION C2L10
J 1
(-4575 4300);
DISPLAY 0.617021 (-4575 4300);
PAINT AQUA (-4575 4300);
FORCEPROP 2 LAST ROOM ST_SATA
J 0
(-4625 4350);
DISPLAY 1.361702 (-4625 4350);
PAINT ORANGE (-4625 4350);
DISPLAY INVISIBLE (-4625 4350);
FORCEPROP 1 LAST PATH I173
J 0
(-4575 4400);
DISPLAY 0.978723 (-4575 4400);
PAINT WHITE (-4575 4400);
DISPLAY INVISIBLE (-4575 4400);
FORCEPROP 2 LAST SEC 1
J 0
(-4575 4450);
DISPLAY 0.680851 (-4575 4450);
PAINT MONO (-4575 4450);
DISPLAY INVISIBLE (-4575 4450);
FORCEPROP 2 LAST SEC_TYPE 0402V
J 0
(-4575 4450);
DISPLAY 1.021277 (-4575 4450);
PAINT ORANGE (-4575 4450);
DISPLAY INVISIBLE (-4575 4450);
FORCEPROP 2 LAST CDS_SEC 1
J 0
(-4575 4350);
PAINT ORANGE (-4575 4350);
DISPLAY INVISIBLE (-4575 4350);
FORCEPROP 2 LAST CDS_LIB dev_discrete
J 0
(-4575 4200);
PAINT ORANGE (-4575 4200);
DISPLAY INVISIBLE (-4575 4200);
FORCEPROP 2 LAST BOM_COST ST_SATA
J 0
(-4625 4300);
DISPLAY 1.361702 (-4625 4300);
PAINT ORANGE (-4625 4300);
DISPLAY INVISIBLE (-4625 4300);
FORCEPROP 2 LAST CDS_LOCATION C2L10
J 1
(-4575 4300);
DISPLAY 0.617021 (-4575 4300);
PAINT AQUA (-4575 4300);
DISPLAY INVISIBLE (-4575 4300);
FORCEADD CAP_A..2
(-4850 4400);
FORCEPROP 1 LAST LOCATION C2L17
J 1
(-4850 4500);
DISPLAY 0.617021 (-4850 4500);
PAINT AQUA (-4850 4500);
FORCEPROP 1 LAST PART_NUMBER A36096-045
J 1
(-4850 4450);
DISPLAY 0.617021 (-4850 4450);
PAINT BLUE (-4850 4450);
FORCEPROP 1 LAST VALUE 0.01UF
J 2
(-4850 4300);
DISPLAY 0.617021 (-4850 4300);
PAINT SKYBLUE (-4850 4300);
FORCEPROP 1 LAST TOLERANCE 10%
J 2
(-4850 4250);
DISPLAY 0.617021 (-4850 4250);
PAINT SKYBLUE (-4850 4250);
FORCEPROP 1 LAST PACK_TYPE 0402V
J 1
(-4850 4200);
DISPLAY 0.617021 (-4850 4200);
PAINT SKYBLUE (-4850 4200);
FORCEPROP 1 LAST VOLTAGE 25V
J 0
(-4850 4300);
DISPLAY 0.617021 (-4850 4300);
PAINT SKYBLUE (-4850 4300);
FORCEPROP 1 LAST MATERIAL X7R
J 0
(-4850 4250);
DISPLAY 0.617021 (-4850 4250);
PAINT SKYBLUE (-4850 4250);
FORCEPROP 1 LASTPIN (-4950 4400) $PN 1
J 0
(-4960 4415);
DISPLAY 0.617021 (-4960 4415);
PAINT ORANGE (-4960 4415);
FORCEPROP 1 LASTPIN (-4750 4400) $PN 2
J 0
(-4765 4415);
DISPLAY 0.617021 (-4765 4415);
PAINT ORANGE (-4765 4415);
FORCEPROP 2 LAST ROOM ST_SATA
J 0
(-4900 4550);
DISPLAY 1.361702 (-4900 4550);
PAINT ORANGE (-4900 4550);
DISPLAY INVISIBLE (-4900 4550);
FORCEPROP 2 LAST CDS_LOCATION C2L17
J 1
(-4850 4500);
DISPLAY 0.617021 (-4850 4500);
PAINT AQUA (-4850 4500);
DISPLAY INVISIBLE (-4850 4500);
FORCEPROP 2 LAST BOM_COST ST_SATA
J 0
(-4900 4500);
DISPLAY 1.361702 (-4900 4500);
PAINT ORANGE (-4900 4500);
DISPLAY INVISIBLE (-4900 4500);
FORCEPROP 2 LAST CDS_LIB dev_discrete
J 0
(-4850 4400);
PAINT ORANGE (-4850 4400);
DISPLAY INVISIBLE (-4850 4400);
FORCEPROP 2 LAST CDS_SEC 1
J 0
(-4850 4550);
PAINT ORANGE (-4850 4550);
DISPLAY INVISIBLE (-4850 4550);
FORCEPROP 2 LAST SEC_TYPE 0402V
J 0
(-4850 4650);
DISPLAY 1.021277 (-4850 4650);
PAINT ORANGE (-4850 4650);
DISPLAY INVISIBLE (-4850 4650);
FORCEPROP 2 LAST SEC 1
J 0
(-4850 4650);
DISPLAY 0.680851 (-4850 4650);
PAINT MONO (-4850 4650);
DISPLAY INVISIBLE (-4850 4650);
FORCEPROP 1 LAST PATH I174
J 0
(-4850 4600);
DISPLAY 0.978723 (-4850 4600);
PAINT WHITE (-4850 4600);
DISPLAY INVISIBLE (-4850 4600);
FORCEADD TAP..6
(-5250 4400);
FORCEPROP 3 LASTPIN (-5200 4400) SIG_NAME SATA6G_PCH_PCIE_UP_SATA_RXN<0>
J 0
(-5190 4410);
DISPLAY 0.659574 (-5190 4410);
PAINT MONO (-5190 4410);
DISPLAY INVISIBLE (-5190 4410);
FORCEPROP 1 LASTPIN (-5200 4400) BN 0
J 0
(-5252 4408);
DISPLAY 0.617021 (-5252 4408);
PAINT GREEN (-5252 4408);
FORCEPROP 2 LAST CDS_LIB mstr_standard
J 0
(-5250 4400);
PAINT ORANGE (-5250 4400);
DISPLAY INVISIBLE (-5250 4400);
FORCEPROP 1 LAST BODY_TYPE PLUMBING
J 0
(-5250 4350);
DISPLAY 0.872340 (-5250 4350);
PAINT GREEN (-5250 4350);
DISPLAY INVISIBLE (-5250 4350);
FORCEPROP 1 LAST HDL_TAP TRUE
J 0
(-4925 4275);
DISPLAY 0.872340 (-4925 4275);
PAINT ORANGE (-4925 4275);
DISPLAY INVISIBLE (-4925 4275);
FORCEPROP 1 LAST PATH I175
J 0
(-5252 4400);
DISPLAY 0.872340 (-5252 4400);
PAINT GREEN (-5252 4400);
DISPLAY INVISIBLE (-5252 4400);
FORCEADD TAP..6
(-5400 4550);
FORCEPROP 3 LASTPIN (-5350 4550) SIG_NAME SATA6G_PCH_PCIE_UP_SATA_RXP<0>
J 0
(-5340 4560);
DISPLAY 0.659574 (-5340 4560);
PAINT MONO (-5340 4560);
DISPLAY INVISIBLE (-5340 4560);
FORCEPROP 1 LASTPIN (-5350 4550) BN 0
J 0
(-5402 4558);
DISPLAY 0.617021 (-5402 4558);
PAINT GREEN (-5402 4558);
FORCEPROP 2 LAST CDS_LIB mstr_standard
J 0
(-5400 4550);
PAINT ORANGE (-5400 4550);
DISPLAY INVISIBLE (-5400 4550);
FORCEPROP 1 LAST BODY_TYPE PLUMBING
J 0
(-5400 4500);
DISPLAY 0.872340 (-5400 4500);
PAINT GREEN (-5400 4500);
DISPLAY INVISIBLE (-5400 4500);
FORCEPROP 1 LAST HDL_TAP TRUE
J 0
(-5075 4425);
DISPLAY 0.872340 (-5075 4425);
PAINT ORANGE (-5075 4425);
DISPLAY INVISIBLE (-5075 4425);
FORCEPROP 1 LAST PATH I176
J 0
(-5402 4550);
DISPLAY 0.872340 (-5402 4550);
PAINT GREEN (-5402 4550);
DISPLAY INVISIBLE (-5402 4550);
FORCEADD TAP..6
(-5400 4200);
FORCEPROP 3 LASTPIN (-5350 4200) SIG_NAME SATA6G_PCH_PCIE_UP_SATA_RXP<1>
J 0
(-5340 4210);
DISPLAY 0.659574 (-5340 4210);
PAINT MONO (-5340 4210);
DISPLAY INVISIBLE (-5340 4210);
FORCEPROP 1 LASTPIN (-5350 4200) BN 1
J 0
(-5402 4208);
DISPLAY 0.617021 (-5402 4208);
PAINT GREEN (-5402 4208);
FORCEPROP 1 LAST PATH I177
J 0
(-5402 4200);
DISPLAY 0.872340 (-5402 4200);
PAINT GREEN (-5402 4200);
DISPLAY INVISIBLE (-5402 4200);
FORCEPROP 1 LAST HDL_TAP TRUE
J 0
(-5075 4075);
DISPLAY 0.872340 (-5075 4075);
PAINT ORANGE (-5075 4075);
DISPLAY INVISIBLE (-5075 4075);
FORCEPROP 1 LAST BODY_TYPE PLUMBING
J 0
(-5400 4150);
DISPLAY 0.872340 (-5400 4150);
PAINT GREEN (-5400 4150);
DISPLAY INVISIBLE (-5400 4150);
FORCEPROP 2 LAST CDS_LIB mstr_standard
J 0
(-5400 4200);
PAINT ORANGE (-5400 4200);
DISPLAY INVISIBLE (-5400 4200);
FORCEADD CAP_A..2
(-4575 3700);
FORCEPROP 1 LAST LOCATION C2L15
J 1
(-4575 3800);
DISPLAY 0.617021 (-4575 3800);
PAINT AQUA (-4575 3800);
FORCEPROP 1 LAST PART_NUMBER A36096-045
J 1
(-4575 3750);
DISPLAY 0.617021 (-4575 3750);
PAINT BLUE (-4575 3750);
FORCEPROP 1 LAST VALUE 0.01UF
J 2
(-4575 3600);
DISPLAY 0.617021 (-4575 3600);
PAINT SKYBLUE (-4575 3600);
FORCEPROP 1 LAST TOLERANCE 10%
J 2
(-4575 3550);
DISPLAY 0.617021 (-4575 3550);
PAINT SKYBLUE (-4575 3550);
FORCEPROP 1 LAST VOLTAGE 25V
J 0
(-4575 3600);
DISPLAY 0.617021 (-4575 3600);
PAINT SKYBLUE (-4575 3600);
FORCEPROP 1 LAST MATERIAL X7R
J 0
(-4575 3550);
DISPLAY 0.617021 (-4575 3550);
PAINT SKYBLUE (-4575 3550);
FORCEPROP 1 LASTPIN (-4475 3700) $PN 2
J 0
(-4490 3715);
DISPLAY 0.617021 (-4490 3715);
PAINT ORANGE (-4490 3715);
FORCEPROP 1 LASTPIN (-4675 3700) $PN 1
J 0
(-4685 3715);
DISPLAY 0.617021 (-4685 3715);
PAINT ORANGE (-4685 3715);
FORCEPROP 1 LAST PACK_TYPE 0402V
J 1
(-4575 3500);
DISPLAY 0.617021 (-4575 3500);
PAINT SKYBLUE (-4575 3500);
FORCEPROP 2 LAST ROOM ST_SATA
J 0
(-4625 3850);
DISPLAY 1.361702 (-4625 3850);
PAINT ORANGE (-4625 3850);
DISPLAY INVISIBLE (-4625 3850);
FORCEPROP 2 LAST CDS_LOCATION C2L15
J 1
(-4575 3800);
DISPLAY 0.617021 (-4575 3800);
PAINT AQUA (-4575 3800);
DISPLAY INVISIBLE (-4575 3800);
FORCEPROP 2 LAST BOM_COST ST_SATA
J 0
(-4625 3800);
DISPLAY 1.361702 (-4625 3800);
PAINT ORANGE (-4625 3800);
DISPLAY INVISIBLE (-4625 3800);
FORCEPROP 2 LAST CDS_LIB dev_discrete
J 0
(-4575 3700);
PAINT ORANGE (-4575 3700);
DISPLAY INVISIBLE (-4575 3700);
FORCEPROP 2 LAST CDS_SEC 1
J 0
(-4575 3850);
PAINT ORANGE (-4575 3850);
DISPLAY INVISIBLE (-4575 3850);
FORCEPROP 2 LAST SEC_TYPE 0402V
J 0
(-4575 3950);
DISPLAY 1.021277 (-4575 3950);
PAINT ORANGE (-4575 3950);
DISPLAY INVISIBLE (-4575 3950);
FORCEPROP 2 LAST SEC 1
J 0
(-4575 3950);
DISPLAY 0.680851 (-4575 3950);
PAINT MONO (-4575 3950);
DISPLAY INVISIBLE (-4575 3950);
FORCEPROP 1 LAST PATH I191
J 0
(-4575 3900);
DISPLAY 0.978723 (-4575 3900);
PAINT WHITE (-4575 3900);
DISPLAY INVISIBLE (-4575 3900);
FORCEADD CAP_A..2
(-4575 3350);
FORCEPROP 1 LAST LOCATION C2L4
J 1
(-4575 3450);
DISPLAY 0.617021 (-4575 3450);
PAINT AQUA (-4575 3450);
FORCEPROP 1 LAST PART_NUMBER A36096-045
J 1
(-4575 3400);
DISPLAY 0.617021 (-4575 3400);
PAINT BLUE (-4575 3400);
FORCEPROP 1 LAST TOLERANCE 10%
J 2
(-4575 3200);
DISPLAY 0.617021 (-4575 3200);
PAINT SKYBLUE (-4575 3200);
FORCEPROP 1 LAST PACK_TYPE 0402V
J 1
(-4575 3150);
DISPLAY 0.617021 (-4575 3150);
PAINT SKYBLUE (-4575 3150);
FORCEPROP 1 LAST VOLTAGE 25V
J 0
(-4575 3250);
DISPLAY 0.617021 (-4575 3250);
PAINT SKYBLUE (-4575 3250);
FORCEPROP 1 LAST MATERIAL X7R
J 0
(-4575 3200);
DISPLAY 0.617021 (-4575 3200);
PAINT SKYBLUE (-4575 3200);
FORCEPROP 1 LASTPIN (-4475 3350) $PN 2
J 0
(-4490 3365);
DISPLAY 0.617021 (-4490 3365);
PAINT ORANGE (-4490 3365);
FORCEPROP 1 LASTPIN (-4675 3350) $PN 1
J 0
(-4685 3365);
DISPLAY 0.617021 (-4685 3365);
PAINT ORANGE (-4685 3365);
FORCEPROP 1 LAST VALUE 0.01UF
J 2
(-4575 3250);
DISPLAY 0.617021 (-4575 3250);
PAINT SKYBLUE (-4575 3250);
FORCEPROP 2 LAST ROOM ST_SATA
J 0
(-4625 3500);
DISPLAY 1.361702 (-4625 3500);
PAINT ORANGE (-4625 3500);
DISPLAY INVISIBLE (-4625 3500);
FORCEPROP 1 LAST PATH I192
J 0
(-4575 3550);
DISPLAY 0.978723 (-4575 3550);
PAINT WHITE (-4575 3550);
DISPLAY INVISIBLE (-4575 3550);
FORCEPROP 2 LAST SEC 1
J 0
(-4575 3600);
DISPLAY 0.680851 (-4575 3600);
PAINT MONO (-4575 3600);
DISPLAY INVISIBLE (-4575 3600);
FORCEPROP 2 LAST SEC_TYPE 0402V
J 0
(-4575 3600);
DISPLAY 1.021277 (-4575 3600);
PAINT ORANGE (-4575 3600);
DISPLAY INVISIBLE (-4575 3600);
FORCEPROP 2 LAST CDS_SEC 1
J 0
(-4575 3500);
PAINT ORANGE (-4575 3500);
DISPLAY INVISIBLE (-4575 3500);
FORCEPROP 2 LAST CDS_LIB dev_discrete
J 0
(-4575 3350);
PAINT ORANGE (-4575 3350);
DISPLAY INVISIBLE (-4575 3350);
FORCEPROP 2 LAST BOM_COST ST_SATA
J 0
(-4625 3450);
DISPLAY 1.361702 (-4625 3450);
PAINT ORANGE (-4625 3450);
DISPLAY INVISIBLE (-4625 3450);
FORCEPROP 2 LAST CDS_LOCATION C2L4
J 1
(-4575 3450);
DISPLAY 0.617021 (-4575 3450);
PAINT AQUA (-4575 3450);
DISPLAY INVISIBLE (-4575 3450);
FORCEADD CAP_A..2
(-4900 3200);
FORCEPROP 1 LAST LOCATION C2L3
J 1
(-4900 3300);
DISPLAY 0.617021 (-4900 3300);
PAINT AQUA (-4900 3300);
FORCEPROP 1 LAST PART_NUMBER A36096-045
J 1
(-4900 3250);
DISPLAY 0.617021 (-4900 3250);
PAINT BLUE (-4900 3250);
FORCEPROP 1 LAST VALUE 0.01UF
J 2
(-4900 3100);
DISPLAY 0.617021 (-4900 3100);
PAINT SKYBLUE (-4900 3100);
FORCEPROP 1 LAST TOLERANCE 10%
J 2
(-4900 3050);
DISPLAY 0.617021 (-4900 3050);
PAINT SKYBLUE (-4900 3050);
FORCEPROP 1 LAST PACK_TYPE 0402V
J 1
(-4900 3000);
DISPLAY 0.617021 (-4900 3000);
PAINT SKYBLUE (-4900 3000);
FORCEPROP 1 LAST VOLTAGE 25V
J 0
(-4900 3100);
DISPLAY 0.617021 (-4900 3100);
PAINT SKYBLUE (-4900 3100);
FORCEPROP 1 LAST MATERIAL X7R
J 0
(-4900 3050);
DISPLAY 0.617021 (-4900 3050);
PAINT SKYBLUE (-4900 3050);
FORCEPROP 1 LASTPIN (-5000 3200) $PN 1
J 0
(-5010 3215);
DISPLAY 0.617021 (-5010 3215);
PAINT ORANGE (-5010 3215);
FORCEPROP 1 LASTPIN (-4800 3200) $PN 2
J 0
(-4815 3215);
DISPLAY 0.617021 (-4815 3215);
PAINT ORANGE (-4815 3215);
FORCEPROP 2 LAST ROOM ST_SATA
J 0
(-4950 3350);
DISPLAY 1.361702 (-4950 3350);
PAINT ORANGE (-4950 3350);
DISPLAY INVISIBLE (-4950 3350);
FORCEPROP 2 LAST CDS_LOCATION C2L3
J 1
(-4900 3300);
DISPLAY 0.617021 (-4900 3300);
PAINT AQUA (-4900 3300);
DISPLAY INVISIBLE (-4900 3300);
FORCEPROP 2 LAST BOM_COST ST_SATA
J 0
(-4950 3300);
DISPLAY 1.361702 (-4950 3300);
PAINT ORANGE (-4950 3300);
DISPLAY INVISIBLE (-4950 3300);
FORCEPROP 2 LAST CDS_LIB dev_discrete
J 0
(-4900 3200);
PAINT ORANGE (-4900 3200);
DISPLAY INVISIBLE (-4900 3200);
FORCEPROP 2 LAST CDS_SEC 1
J 0
(-4900 3350);
PAINT ORANGE (-4900 3350);
DISPLAY INVISIBLE (-4900 3350);
FORCEPROP 2 LAST SEC_TYPE 0402V
J 0
(-4900 3450);
DISPLAY 1.021277 (-4900 3450);
PAINT ORANGE (-4900 3450);
DISPLAY INVISIBLE (-4900 3450);
FORCEPROP 2 LAST SEC 1
J 0
(-4900 3450);
DISPLAY 0.680851 (-4900 3450);
PAINT MONO (-4900 3450);
DISPLAY INVISIBLE (-4900 3450);
FORCEPROP 1 LAST PATH I194
J 0
(-4900 3400);
DISPLAY 0.978723 (-4900 3400);
PAINT WHITE (-4900 3400);
DISPLAY INVISIBLE (-4900 3400);
FORCEADD CAP_A..2
(-4600 2900);
FORCEPROP 1 LAST LOCATION C2L20
J 1
(-4600 3000);
DISPLAY 0.617021 (-4600 3000);
PAINT AQUA (-4600 3000);
FORCEPROP 1 LAST PART_NUMBER A36096-045
J 1
(-4600 2950);
DISPLAY 0.617021 (-4600 2950);
PAINT BLUE (-4600 2950);
FORCEPROP 1 LAST VALUE 0.01UF
J 2
(-4600 2800);
DISPLAY 0.617021 (-4600 2800);
PAINT SKYBLUE (-4600 2800);
FORCEPROP 1 LAST TOLERANCE 10%
J 2
(-4600 2750);
DISPLAY 0.617021 (-4600 2750);
PAINT SKYBLUE (-4600 2750);
FORCEPROP 1 LAST PACK_TYPE 0402V
J 1
(-4600 2700);
DISPLAY 0.617021 (-4600 2700);
PAINT SKYBLUE (-4600 2700);
FORCEPROP 1 LAST VOLTAGE 25V
J 0
(-4600 2800);
DISPLAY 0.617021 (-4600 2800);
PAINT SKYBLUE (-4600 2800);
FORCEPROP 1 LAST MATERIAL X7R
J 0
(-4600 2750);
DISPLAY 0.617021 (-4600 2750);
PAINT SKYBLUE (-4600 2750);
FORCEPROP 1 LASTPIN (-4700 2900) $PN 1
J 0
(-4710 2915);
DISPLAY 0.617021 (-4710 2915);
PAINT ORANGE (-4710 2915);
FORCEPROP 1 LASTPIN (-4500 2900) $PN 2
J 0
(-4515 2915);
DISPLAY 0.617021 (-4515 2915);
PAINT ORANGE (-4515 2915);
FORCEPROP 2 LAST ROOM ST_SATA
J 0
(-4650 3050);
DISPLAY 1.361702 (-4650 3050);
PAINT ORANGE (-4650 3050);
DISPLAY INVISIBLE (-4650 3050);
FORCEPROP 2 LAST CDS_LOCATION C2L20
J 1
(-4600 3000);
DISPLAY 0.617021 (-4600 3000);
PAINT AQUA (-4600 3000);
DISPLAY INVISIBLE (-4600 3000);
FORCEPROP 2 LAST BOM_COST ST_SATA
J 0
(-4650 3000);
DISPLAY 1.361702 (-4650 3000);
PAINT ORANGE (-4650 3000);
DISPLAY INVISIBLE (-4650 3000);
FORCEPROP 2 LAST CDS_LIB dev_discrete
J 0
(-4600 2900);
PAINT ORANGE (-4600 2900);
DISPLAY INVISIBLE (-4600 2900);
FORCEPROP 2 LAST CDS_SEC 1
J 0
(-4600 3050);
PAINT ORANGE (-4600 3050);
DISPLAY INVISIBLE (-4600 3050);
FORCEPROP 2 LAST SEC_TYPE 0402V
J 0
(-4600 3150);
DISPLAY 1.021277 (-4600 3150);
PAINT ORANGE (-4600 3150);
DISPLAY INVISIBLE (-4600 3150);
FORCEPROP 2 LAST SEC 1
J 0
(-4600 3150);
DISPLAY 0.680851 (-4600 3150);
PAINT MONO (-4600 3150);
DISPLAY INVISIBLE (-4600 3150);
FORCEPROP 1 LAST PATH I195
J 0
(-4600 3100);
DISPLAY 0.978723 (-4600 3100);
PAINT WHITE (-4600 3100);
DISPLAY INVISIBLE (-4600 3100);
FORCEADD CAP_A..2
(-4575 2550);
FORCEPROP 1 LAST TOLERANCE 10%
J 2
(-4575 2400);
DISPLAY 0.617021 (-4575 2400);
PAINT SKYBLUE (-4575 2400);
FORCEPROP 1 LAST PACK_TYPE 0402V
J 1
(-4575 2350);
DISPLAY 0.617021 (-4575 2350);
PAINT SKYBLUE (-4575 2350);
FORCEPROP 1 LAST VOLTAGE 25V
J 0
(-4575 2450);
DISPLAY 0.617021 (-4575 2450);
PAINT SKYBLUE (-4575 2450);
FORCEPROP 1 LAST MATERIAL X7R
J 0
(-4575 2400);
DISPLAY 0.617021 (-4575 2400);
PAINT SKYBLUE (-4575 2400);
FORCEPROP 1 LASTPIN (-4475 2550) $PN 2
J 0
(-4490 2565);
DISPLAY 0.617021 (-4490 2565);
PAINT ORANGE (-4490 2565);
FORCEPROP 1 LASTPIN (-4675 2550) $PN 1
J 0
(-4685 2565);
DISPLAY 0.617021 (-4685 2565);
PAINT ORANGE (-4685 2565);
FORCEPROP 1 LAST VALUE 0.01UF
J 2
(-4575 2450);
DISPLAY 0.617021 (-4575 2450);
PAINT SKYBLUE (-4575 2450);
FORCEPROP 1 LAST PART_NUMBER A36096-045
J 1
(-4575 2600);
DISPLAY 0.617021 (-4575 2600);
PAINT BLUE (-4575 2600);
FORCEPROP 1 LAST LOCATION C2L12
J 1
(-4575 2650);
DISPLAY 0.617021 (-4575 2650);
PAINT AQUA (-4575 2650);
FORCEPROP 2 LAST ROOM ST_SATA
J 0
(-4625 2700);
DISPLAY 1.361702 (-4625 2700);
PAINT ORANGE (-4625 2700);
DISPLAY INVISIBLE (-4625 2700);
FORCEPROP 1 LAST PATH I196
J 0
(-4575 2750);
DISPLAY 0.978723 (-4575 2750);
PAINT WHITE (-4575 2750);
DISPLAY INVISIBLE (-4575 2750);
FORCEPROP 2 LAST SEC 1
J 0
(-4575 2800);
DISPLAY 0.680851 (-4575 2800);
PAINT MONO (-4575 2800);
DISPLAY INVISIBLE (-4575 2800);
FORCEPROP 2 LAST SEC_TYPE 0402V
J 0
(-4575 2800);
DISPLAY 1.021277 (-4575 2800);
PAINT ORANGE (-4575 2800);
DISPLAY INVISIBLE (-4575 2800);
FORCEPROP 2 LAST CDS_SEC 1
J 0
(-4575 2700);
PAINT ORANGE (-4575 2700);
DISPLAY INVISIBLE (-4575 2700);
FORCEPROP 2 LAST CDS_LIB dev_discrete
J 0
(-4575 2550);
PAINT ORANGE (-4575 2550);
DISPLAY INVISIBLE (-4575 2550);
FORCEPROP 2 LAST BOM_COST ST_SATA
J 0
(-4625 2650);
DISPLAY 1.361702 (-4625 2650);
PAINT ORANGE (-4625 2650);
DISPLAY INVISIBLE (-4625 2650);
FORCEPROP 2 LAST CDS_LOCATION C2L12
J 1
(-4575 2650);
DISPLAY 0.617021 (-4575 2650);
PAINT AQUA (-4575 2650);
DISPLAY INVISIBLE (-4575 2650);
FORCEADD CAP_A..2
(-4950 2750);
FORCEPROP 1 LAST VALUE 0.01UF
J 2
(-4950 2650);
DISPLAY 0.617021 (-4950 2650);
PAINT SKYBLUE (-4950 2650);
FORCEPROP 1 LAST TOLERANCE 10%
J 2
(-4950 2600);
DISPLAY 0.617021 (-4950 2600);
PAINT SKYBLUE (-4950 2600);
FORCEPROP 1 LAST PACK_TYPE 0402V
J 1
(-4950 2550);
DISPLAY 0.617021 (-4950 2550);
PAINT SKYBLUE (-4950 2550);
FORCEPROP 1 LAST VOLTAGE 25V
J 0
(-4950 2650);
DISPLAY 0.617021 (-4950 2650);
PAINT SKYBLUE (-4950 2650);
FORCEPROP 1 LAST MATERIAL X7R
J 0
(-4950 2600);
DISPLAY 0.617021 (-4950 2600);
PAINT SKYBLUE (-4950 2600);
FORCEPROP 1 LASTPIN (-5050 2750) $PN 1
J 0
(-5060 2765);
DISPLAY 0.617021 (-5060 2765);
PAINT ORANGE (-5060 2765);
FORCEPROP 1 LASTPIN (-4850 2750) $PN 2
J 0
(-4865 2765);
DISPLAY 0.617021 (-4865 2765);
PAINT ORANGE (-4865 2765);
FORCEPROP 1 LAST PART_NUMBER A36096-045
J 1
(-4950 2800);
DISPLAY 0.617021 (-4950 2800);
PAINT BLUE (-4950 2800);
FORCEPROP 1 LAST LOCATION C2L18
J 1
(-4950 2850);
DISPLAY 0.617021 (-4950 2850);
PAINT AQUA (-4950 2850);
FORCEPROP 2 LAST ROOM ST_SATA
J 0
(-5000 2900);
DISPLAY 1.361702 (-5000 2900);
PAINT ORANGE (-5000 2900);
DISPLAY INVISIBLE (-5000 2900);
FORCEPROP 2 LAST CDS_LOCATION C2L18
J 1
(-4950 2850);
DISPLAY 0.617021 (-4950 2850);
PAINT AQUA (-4950 2850);
DISPLAY INVISIBLE (-4950 2850);
FORCEPROP 2 LAST BOM_COST ST_SATA
J 0
(-5000 2850);
DISPLAY 1.361702 (-5000 2850);
PAINT ORANGE (-5000 2850);
DISPLAY INVISIBLE (-5000 2850);
FORCEPROP 2 LAST CDS_LIB dev_discrete
J 0
(-4950 2750);
PAINT ORANGE (-4950 2750);
DISPLAY INVISIBLE (-4950 2750);
FORCEPROP 2 LAST CDS_SEC 1
J 0
(-4950 2900);
PAINT ORANGE (-4950 2900);
DISPLAY INVISIBLE (-4950 2900);
FORCEPROP 2 LAST SEC_TYPE 0402V
J 0
(-4950 3000);
DISPLAY 1.021277 (-4950 3000);
PAINT ORANGE (-4950 3000);
DISPLAY INVISIBLE (-4950 3000);
FORCEPROP 2 LAST SEC 1
J 0
(-4950 3000);
DISPLAY 0.680851 (-4950 3000);
PAINT MONO (-4950 3000);
DISPLAY INVISIBLE (-4950 3000);
FORCEPROP 1 LAST PATH I197
J 0
(-4950 2950);
DISPLAY 0.978723 (-4950 2950);
PAINT WHITE (-4950 2950);
DISPLAY INVISIBLE (-4950 2950);
FORCEADD TAP..6
(-5250 3550);
FORCEPROP 3 LASTPIN (-5200 3550) SIG_NAME SATA6G_PCH_PCIE_UP_SATA_RXN<2>
J 0
(-5190 3560);
DISPLAY 0.659574 (-5190 3560);
PAINT MONO (-5190 3560);
DISPLAY INVISIBLE (-5190 3560);
FORCEPROP 1 LASTPIN (-5200 3550) BN 2
J 0
(-5252 3558);
DISPLAY 0.617021 (-5252 3558);
PAINT GREEN (-5252 3558);
FORCEPROP 2 LAST CDS_LIB mstr_standard
J 0
(-5250 3550);
PAINT ORANGE (-5250 3550);
DISPLAY INVISIBLE (-5250 3550);
FORCEPROP 1 LAST BODY_TYPE PLUMBING
J 0
(-5250 3500);
DISPLAY 0.872340 (-5250 3500);
PAINT GREEN (-5250 3500);
DISPLAY INVISIBLE (-5250 3500);
FORCEPROP 1 LAST HDL_TAP TRUE
J 0
(-4925 3425);
DISPLAY 0.872340 (-4925 3425);
PAINT ORANGE (-4925 3425);
DISPLAY INVISIBLE (-4925 3425);
FORCEPROP 1 LAST PATH I198
J 0
(-5252 3550);
DISPLAY 0.872340 (-5252 3550);
PAINT GREEN (-5252 3550);
DISPLAY INVISIBLE (-5252 3550);
FORCEADD TAP..6
(-5400 3700);
FORCEPROP 3 LASTPIN (-5350 3700) SIG_NAME SATA6G_PCH_PCIE_UP_SATA_RXP<2>
J 0
(-5340 3710);
DISPLAY 0.659574 (-5340 3710);
PAINT MONO (-5340 3710);
DISPLAY INVISIBLE (-5340 3710);
FORCEPROP 1 LASTPIN (-5350 3700) BN 2
J 0
(-5402 3708);
DISPLAY 0.617021 (-5402 3708);
PAINT GREEN (-5402 3708);
FORCEPROP 2 LAST CDS_LIB mstr_standard
J 0
(-5400 3700);
PAINT ORANGE (-5400 3700);
DISPLAY INVISIBLE (-5400 3700);
FORCEPROP 1 LAST BODY_TYPE PLUMBING
J 0
(-5400 3650);
DISPLAY 0.872340 (-5400 3650);
PAINT GREEN (-5400 3650);
DISPLAY INVISIBLE (-5400 3650);
FORCEPROP 1 LAST HDL_TAP TRUE
J 0
(-5075 3575);
DISPLAY 0.872340 (-5075 3575);
PAINT ORANGE (-5075 3575);
DISPLAY INVISIBLE (-5075 3575);
FORCEPROP 1 LAST PATH I199
J 0
(-5402 3700);
DISPLAY 0.872340 (-5402 3700);
PAINT GREEN (-5402 3700);
DISPLAY INVISIBLE (-5402 3700);
FORCEADD TAP..6
(-5400 3350);
FORCEPROP 3 LASTPIN (-5350 3350) SIG_NAME SATA6G_PCH_PCIE_UP_SATA_RXP<3>
J 0
(-5340 3360);
DISPLAY 0.659574 (-5340 3360);
PAINT MONO (-5340 3360);
DISPLAY INVISIBLE (-5340 3360);
FORCEPROP 1 LASTPIN (-5350 3350) BN 3
J 0
(-5402 3358);
DISPLAY 0.617021 (-5402 3358);
PAINT GREEN (-5402 3358);
FORCEPROP 1 LAST PATH I200
J 0
(-5402 3350);
DISPLAY 0.872340 (-5402 3350);
PAINT GREEN (-5402 3350);
DISPLAY INVISIBLE (-5402 3350);
FORCEPROP 1 LAST HDL_TAP TRUE
J 0
(-5075 3225);
DISPLAY 0.872340 (-5075 3225);
PAINT ORANGE (-5075 3225);
DISPLAY INVISIBLE (-5075 3225);
FORCEPROP 1 LAST BODY_TYPE PLUMBING
J 0
(-5400 3300);
DISPLAY 0.872340 (-5400 3300);
PAINT GREEN (-5400 3300);
DISPLAY INVISIBLE (-5400 3300);
FORCEPROP 2 LAST CDS_LIB mstr_standard
J 0
(-5400 3350);
PAINT ORANGE (-5400 3350);
DISPLAY INVISIBLE (-5400 3350);
FORCEADD TAP..6
(-5250 3200);
FORCEPROP 3 LASTPIN (-5200 3200) SIG_NAME SATA6G_PCH_PCIE_UP_SATA_RXN<3>
J 0
(-5190 3210);
DISPLAY 0.659574 (-5190 3210);
PAINT MONO (-5190 3210);
DISPLAY INVISIBLE (-5190 3210);
FORCEPROP 1 LASTPIN (-5200 3200) BN 3
J 0
(-5252 3208);
DISPLAY 0.617021 (-5252 3208);
PAINT GREEN (-5252 3208);
FORCEPROP 1 LAST PATH I201
J 0
(-5252 3200);
DISPLAY 0.872340 (-5252 3200);
PAINT GREEN (-5252 3200);
DISPLAY INVISIBLE (-5252 3200);
FORCEPROP 1 LAST HDL_TAP TRUE
J 0
(-4925 3075);
DISPLAY 0.872340 (-4925 3075);
PAINT ORANGE (-4925 3075);
DISPLAY INVISIBLE (-4925 3075);
FORCEPROP 1 LAST BODY_TYPE PLUMBING
J 0
(-5250 3150);
DISPLAY 0.872340 (-5250 3150);
PAINT GREEN (-5250 3150);
DISPLAY INVISIBLE (-5250 3150);
FORCEPROP 2 LAST CDS_LIB mstr_standard
J 0
(-5250 3200);
PAINT ORANGE (-5250 3200);
DISPLAY INVISIBLE (-5250 3200);
FORCEADD TAP..6
(-5400 2900);
FORCEPROP 3 LASTPIN (-5350 2900) SIG_NAME SATA6G_PCH_PCIE_UP_SATA_RXP<4>
J 0
(-5340 2910);
DISPLAY 0.659574 (-5340 2910);
PAINT MONO (-5340 2910);
DISPLAY INVISIBLE (-5340 2910);
FORCEPROP 1 LASTPIN (-5350 2900) BN 4
J 0
(-5402 2908);
DISPLAY 0.617021 (-5402 2908);
PAINT GREEN (-5402 2908);
FORCEPROP 2 LAST CDS_LIB mstr_standard
J 0
(-5400 2900);
PAINT ORANGE (-5400 2900);
DISPLAY INVISIBLE (-5400 2900);
FORCEPROP 1 LAST BODY_TYPE PLUMBING
J 0
(-5400 2850);
DISPLAY 0.872340 (-5400 2850);
PAINT GREEN (-5400 2850);
DISPLAY INVISIBLE (-5400 2850);
FORCEPROP 1 LAST HDL_TAP TRUE
J 0
(-5075 2775);
DISPLAY 0.872340 (-5075 2775);
PAINT ORANGE (-5075 2775);
DISPLAY INVISIBLE (-5075 2775);
FORCEPROP 1 LAST PATH I202
J 0
(-5402 2900);
DISPLAY 0.872340 (-5402 2900);
PAINT GREEN (-5402 2900);
DISPLAY INVISIBLE (-5402 2900);
FORCEADD TAP..6
(-5400 2550);
FORCEPROP 3 LASTPIN (-5350 2550) SIG_NAME SATA6G_PCH_PCIE_UP_SATA_RXP<5>
J 0
(-5340 2560);
DISPLAY 0.659574 (-5340 2560);
PAINT MONO (-5340 2560);
DISPLAY INVISIBLE (-5340 2560);
FORCEPROP 1 LASTPIN (-5350 2550) BN 5
J 0
(-5402 2558);
DISPLAY 0.617021 (-5402 2558);
PAINT GREEN (-5402 2558);
FORCEPROP 1 LAST PATH I203
J 0
(-5402 2550);
DISPLAY 0.872340 (-5402 2550);
PAINT GREEN (-5402 2550);
DISPLAY INVISIBLE (-5402 2550);
FORCEPROP 1 LAST HDL_TAP TRUE
J 0
(-5075 2425);
DISPLAY 0.872340 (-5075 2425);
PAINT ORANGE (-5075 2425);
DISPLAY INVISIBLE (-5075 2425);
FORCEPROP 1 LAST BODY_TYPE PLUMBING
J 0
(-5400 2500);
DISPLAY 0.872340 (-5400 2500);
PAINT GREEN (-5400 2500);
DISPLAY INVISIBLE (-5400 2500);
FORCEPROP 2 LAST CDS_LIB mstr_standard
J 0
(-5400 2550);
PAINT ORANGE (-5400 2550);
DISPLAY INVISIBLE (-5400 2550);
FORCEADD TAP..6
(-5250 2750);
FORCEPROP 3 LASTPIN (-5200 2750) SIG_NAME SATA6G_PCH_PCIE_UP_SATA_RXN<4>
J 0
(-5190 2760);
DISPLAY 0.659574 (-5190 2760);
PAINT MONO (-5190 2760);
DISPLAY INVISIBLE (-5190 2760);
FORCEPROP 1 LASTPIN (-5200 2750) BN 4
J 0
(-5252 2758);
DISPLAY 0.617021 (-5252 2758);
PAINT GREEN (-5252 2758);
FORCEPROP 2 LAST CDS_LIB mstr_standard
J 0
(-5250 2750);
PAINT ORANGE (-5250 2750);
DISPLAY INVISIBLE (-5250 2750);
FORCEPROP 1 LAST BODY_TYPE PLUMBING
J 0
(-5250 2700);
DISPLAY 0.872340 (-5250 2700);
PAINT GREEN (-5250 2700);
DISPLAY INVISIBLE (-5250 2700);
FORCEPROP 1 LAST HDL_TAP TRUE
J 0
(-4925 2625);
DISPLAY 0.872340 (-4925 2625);
PAINT ORANGE (-4925 2625);
DISPLAY INVISIBLE (-4925 2625);
FORCEPROP 1 LAST PATH I204
J 0
(-5252 2750);
DISPLAY 0.872340 (-5252 2750);
PAINT GREEN (-5252 2750);
DISPLAY INVISIBLE (-5252 2750);
FORCEADD CAP_A..2
(-4575 2050);
FORCEPROP 1 LAST LOCATION C2L16
J 1
(-4575 2150);
DISPLAY 0.617021 (-4575 2150);
PAINT AQUA (-4575 2150);
FORCEPROP 1 LAST PART_NUMBER A36096-045
J 1
(-4575 2100);
DISPLAY 0.617021 (-4575 2100);
PAINT BLUE (-4575 2100);
FORCEPROP 1 LAST TOLERANCE 10%
J 2
(-4575 1900);
DISPLAY 0.617021 (-4575 1900);
PAINT SKYBLUE (-4575 1900);
FORCEPROP 1 LAST PACK_TYPE 0402V
J 1
(-4575 1850);
DISPLAY 0.617021 (-4575 1850);
PAINT SKYBLUE (-4575 1850);
FORCEPROP 1 LAST VOLTAGE 25V
J 0
(-4575 1950);
DISPLAY 0.617021 (-4575 1950);
PAINT SKYBLUE (-4575 1950);
FORCEPROP 1 LAST MATERIAL X7R
J 0
(-4575 1900);
DISPLAY 0.617021 (-4575 1900);
PAINT SKYBLUE (-4575 1900);
FORCEPROP 1 LASTPIN (-4675 2050) $PN 1
J 0
(-4685 2065);
DISPLAY 0.617021 (-4685 2065);
PAINT ORANGE (-4685 2065);
FORCEPROP 1 LASTPIN (-4475 2050) $PN 2
J 0
(-4490 2065);
DISPLAY 0.617021 (-4490 2065);
PAINT ORANGE (-4490 2065);
FORCEPROP 1 LAST VALUE 0.01UF
J 2
(-4575 1950);
DISPLAY 0.617021 (-4575 1950);
PAINT SKYBLUE (-4575 1950);
FORCEPROP 2 LAST ROOM ST_SATA
J 0
(-4625 2200);
DISPLAY 1.361702 (-4625 2200);
PAINT ORANGE (-4625 2200);
DISPLAY INVISIBLE (-4625 2200);
FORCEPROP 2 LAST CDS_LOCATION C2L16
J 1
(-4575 2150);
DISPLAY 0.617021 (-4575 2150);
PAINT AQUA (-4575 2150);
DISPLAY INVISIBLE (-4575 2150);
FORCEPROP 2 LAST BOM_COST ST_SATA
J 0
(-4625 2150);
DISPLAY 1.361702 (-4625 2150);
PAINT ORANGE (-4625 2150);
DISPLAY INVISIBLE (-4625 2150);
FORCEPROP 2 LAST CDS_LIB dev_discrete
J 0
(-4575 2050);
PAINT ORANGE (-4575 2050);
DISPLAY INVISIBLE (-4575 2050);
FORCEPROP 2 LAST CDS_SEC 1
J 0
(-4575 2200);
PAINT ORANGE (-4575 2200);
DISPLAY INVISIBLE (-4575 2200);
FORCEPROP 2 LAST SEC_TYPE 0402V
J 0
(-4575 2300);
DISPLAY 1.021277 (-4575 2300);
PAINT ORANGE (-4575 2300);
DISPLAY INVISIBLE (-4575 2300);
FORCEPROP 2 LAST SEC 1
J 0
(-4575 2300);
DISPLAY 0.680851 (-4575 2300);
PAINT MONO (-4575 2300);
DISPLAY INVISIBLE (-4575 2300);
FORCEPROP 1 LAST PATH I205
J 0
(-4575 2250);
DISPLAY 0.978723 (-4575 2250);
PAINT WHITE (-4575 2250);
DISPLAY INVISIBLE (-4575 2250);
FORCEADD CAP_A..2
(-4575 1700);
FORCEPROP 1 LAST LOCATION C2L7
J 1
(-4575 1800);
DISPLAY 0.617021 (-4575 1800);
PAINT AQUA (-4575 1800);
FORCEPROP 1 LAST PART_NUMBER A36096-045
J 1
(-4575 1750);
DISPLAY 0.617021 (-4575 1750);
PAINT BLUE (-4575 1750);
FORCEPROP 1 LAST VALUE 0.01UF
J 2
(-4575 1600);
DISPLAY 0.617021 (-4575 1600);
PAINT SKYBLUE (-4575 1600);
FORCEPROP 1 LAST TOLERANCE 10%
J 2
(-4575 1550);
DISPLAY 0.617021 (-4575 1550);
PAINT SKYBLUE (-4575 1550);
FORCEPROP 1 LASTPIN (-4475 1700) $PN 2
J 0
(-4490 1715);
DISPLAY 0.617021 (-4490 1715);
PAINT ORANGE (-4490 1715);
FORCEPROP 1 LASTPIN (-4675 1700) $PN 1
J 0
(-4685 1715);
DISPLAY 0.617021 (-4685 1715);
PAINT ORANGE (-4685 1715);
FORCEPROP 1 LAST VOLTAGE 25V
J 0
(-4575 1600);
DISPLAY 0.617021 (-4575 1600);
PAINT SKYBLUE (-4575 1600);
FORCEPROP 1 LAST MATERIAL X7R
J 0
(-4575 1550);
DISPLAY 0.617021 (-4575 1550);
PAINT SKYBLUE (-4575 1550);
FORCEPROP 1 LAST PACK_TYPE 0402V
J 1
(-4575 1500);
DISPLAY 0.617021 (-4575 1500);
PAINT SKYBLUE (-4575 1500);
FORCEPROP 2 LAST ROOM ST_SATA
J 0
(-4625 1850);
DISPLAY 1.361702 (-4625 1850);
PAINT ORANGE (-4625 1850);
DISPLAY INVISIBLE (-4625 1850);
FORCEPROP 1 LAST PATH I206
J 0
(-4575 1900);
DISPLAY 0.978723 (-4575 1900);
PAINT WHITE (-4575 1900);
DISPLAY INVISIBLE (-4575 1900);
FORCEPROP 2 LAST SEC 1
J 0
(-4575 1950);
DISPLAY 0.680851 (-4575 1950);
PAINT MONO (-4575 1950);
DISPLAY INVISIBLE (-4575 1950);
FORCEPROP 2 LAST SEC_TYPE 0402V
J 0
(-4575 1950);
DISPLAY 1.021277 (-4575 1950);
PAINT ORANGE (-4575 1950);
DISPLAY INVISIBLE (-4575 1950);
FORCEPROP 2 LAST CDS_SEC 1
J 0
(-4575 1850);
PAINT ORANGE (-4575 1850);
DISPLAY INVISIBLE (-4575 1850);
FORCEPROP 2 LAST CDS_LIB dev_discrete
J 0
(-4575 1700);
PAINT ORANGE (-4575 1700);
DISPLAY INVISIBLE (-4575 1700);
FORCEPROP 2 LAST BOM_COST ST_SATA
J 0
(-4625 1800);
DISPLAY 1.361702 (-4625 1800);
PAINT ORANGE (-4625 1800);
DISPLAY INVISIBLE (-4625 1800);
FORCEPROP 2 LAST CDS_LOCATION C2L7
J 1
(-4575 1800);
DISPLAY 0.617021 (-4575 1800);
PAINT AQUA (-4575 1800);
DISPLAY INVISIBLE (-4575 1800);
FORCEADD CAP_A..2
(-4950 2400);
FORCEPROP 1 LAST LOCATION C2L9
J 1
(-4950 2500);
DISPLAY 0.617021 (-4950 2500);
PAINT AQUA (-4950 2500);
FORCEPROP 1 LAST VALUE 0.01UF
J 2
(-4950 2300);
DISPLAY 0.617021 (-4950 2300);
PAINT SKYBLUE (-4950 2300);
FORCEPROP 1 LAST TOLERANCE 10%
J 2
(-4950 2250);
DISPLAY 0.617021 (-4950 2250);
PAINT SKYBLUE (-4950 2250);
FORCEPROP 1 LAST PACK_TYPE 0402V
J 1
(-4950 2200);
DISPLAY 0.617021 (-4950 2200);
PAINT SKYBLUE (-4950 2200);
FORCEPROP 1 LAST VOLTAGE 25V
J 0
(-4950 2300);
DISPLAY 0.617021 (-4950 2300);
PAINT SKYBLUE (-4950 2300);
FORCEPROP 1 LAST MATERIAL X7R
J 0
(-4950 2250);
DISPLAY 0.617021 (-4950 2250);
PAINT SKYBLUE (-4950 2250);
FORCEPROP 1 LASTPIN (-5050 2400) $PN 1
J 0
(-5060 2415);
DISPLAY 0.617021 (-5060 2415);
PAINT ORANGE (-5060 2415);
FORCEPROP 1 LASTPIN (-4850 2400) $PN 2
J 0
(-4865 2415);
DISPLAY 0.617021 (-4865 2415);
PAINT ORANGE (-4865 2415);
FORCEPROP 1 LAST PART_NUMBER A36096-045
J 1
(-4950 2450);
DISPLAY 0.617021 (-4950 2450);
PAINT BLUE (-4950 2450);
FORCEPROP 2 LAST ROOM ST_SATA
J 0
(-5000 2550);
DISPLAY 1.361702 (-5000 2550);
PAINT ORANGE (-5000 2550);
DISPLAY INVISIBLE (-5000 2550);
FORCEPROP 2 LAST CDS_LOCATION C2L9
J 1
(-4950 2500);
DISPLAY 0.617021 (-4950 2500);
PAINT AQUA (-4950 2500);
DISPLAY INVISIBLE (-4950 2500);
FORCEPROP 2 LAST BOM_COST ST_SATA
J 0
(-5000 2500);
DISPLAY 1.361702 (-5000 2500);
PAINT ORANGE (-5000 2500);
DISPLAY INVISIBLE (-5000 2500);
FORCEPROP 2 LAST CDS_LIB dev_discrete
J 0
(-4950 2400);
PAINT ORANGE (-4950 2400);
DISPLAY INVISIBLE (-4950 2400);
FORCEPROP 2 LAST CDS_SEC 1
J 0
(-4950 2550);
PAINT ORANGE (-4950 2550);
DISPLAY INVISIBLE (-4950 2550);
FORCEPROP 2 LAST SEC_TYPE 0402V
J 0
(-4950 2650);
DISPLAY 1.021277 (-4950 2650);
PAINT ORANGE (-4950 2650);
DISPLAY INVISIBLE (-4950 2650);
FORCEPROP 2 LAST SEC 1
J 0
(-4950 2650);
DISPLAY 0.680851 (-4950 2650);
PAINT MONO (-4950 2650);
DISPLAY INVISIBLE (-4950 2650);
FORCEPROP 1 LAST PATH I207
J 0
(-4950 2600);
DISPLAY 0.978723 (-4950 2600);
PAINT WHITE (-4950 2600);
DISPLAY INVISIBLE (-4950 2600);
FORCEADD CAP_A..2
(-4975 1850);
FORCEPROP 1 LAST LOCATION C2L14
J 1
(-4975 1950);
DISPLAY 0.617021 (-4975 1950);
PAINT AQUA (-4975 1950);
FORCEPROP 1 LAST PART_NUMBER A36096-045
J 1
(-4975 1900);
DISPLAY 0.617021 (-4975 1900);
PAINT BLUE (-4975 1900);
FORCEPROP 1 LAST VALUE 0.01UF
J 2
(-4975 1750);
DISPLAY 0.617021 (-4975 1750);
PAINT SKYBLUE (-4975 1750);
FORCEPROP 1 LAST TOLERANCE 10%
J 2
(-4975 1700);
DISPLAY 0.617021 (-4975 1700);
PAINT SKYBLUE (-4975 1700);
FORCEPROP 1 LAST VOLTAGE 25V
J 0
(-4975 1750);
DISPLAY 0.617021 (-4975 1750);
PAINT SKYBLUE (-4975 1750);
FORCEPROP 1 LASTPIN (-5075 1850) $PN 1
J 0
(-5085 1865);
DISPLAY 0.617021 (-5085 1865);
PAINT ORANGE (-5085 1865);
FORCEPROP 1 LASTPIN (-4875 1850) $PN 2
J 0
(-4890 1865);
DISPLAY 0.617021 (-4890 1865);
PAINT ORANGE (-4890 1865);
FORCEPROP 1 LAST PACK_TYPE 0402V
J 1
(-4975 1650);
DISPLAY 0.617021 (-4975 1650);
PAINT SKYBLUE (-4975 1650);
FORCEPROP 1 LAST MATERIAL X7R
J 0
(-4975 1700);
DISPLAY 0.617021 (-4975 1700);
PAINT SKYBLUE (-4975 1700);
FORCEPROP 2 LAST ROOM ST_SATA
J 0
(-5025 2000);
DISPLAY 1.361702 (-5025 2000);
PAINT ORANGE (-5025 2000);
DISPLAY INVISIBLE (-5025 2000);
FORCEPROP 2 LAST CDS_LOCATION C2L14
J 1
(-4975 1950);
DISPLAY 0.617021 (-4975 1950);
PAINT AQUA (-4975 1950);
DISPLAY INVISIBLE (-4975 1950);
FORCEPROP 2 LAST BOM_COST ST_SATA
J 0
(-5025 1950);
DISPLAY 1.361702 (-5025 1950);
PAINT ORANGE (-5025 1950);
DISPLAY INVISIBLE (-5025 1950);
FORCEPROP 2 LAST CDS_LIB dev_discrete
J 0
(-4975 1850);
PAINT ORANGE (-4975 1850);
DISPLAY INVISIBLE (-4975 1850);
FORCEPROP 2 LAST CDS_SEC 1
J 0
(-4975 2000);
PAINT ORANGE (-4975 2000);
DISPLAY INVISIBLE (-4975 2000);
FORCEPROP 2 LAST SEC_TYPE 0402V
J 0
(-4975 2100);
DISPLAY 1.021277 (-4975 2100);
PAINT ORANGE (-4975 2100);
DISPLAY INVISIBLE (-4975 2100);
FORCEPROP 2 LAST SEC 1
J 0
(-4975 2100);
DISPLAY 0.680851 (-4975 2100);
PAINT MONO (-4975 2100);
DISPLAY INVISIBLE (-4975 2100);
FORCEPROP 1 LAST PATH I208
J 0
(-4975 2050);
DISPLAY 0.978723 (-4975 2050);
PAINT WHITE (-4975 2050);
DISPLAY INVISIBLE (-4975 2050);
FORCEADD CAP_A..2
(-4975 1500);
FORCEPROP 1 LAST VALUE 0.01UF
J 2
(-4975 1400);
DISPLAY 0.617021 (-4975 1400);
PAINT SKYBLUE (-4975 1400);
FORCEPROP 1 LAST TOLERANCE 10%
J 2
(-4975 1350);
DISPLAY 0.617021 (-4975 1350);
PAINT SKYBLUE (-4975 1350);
FORCEPROP 1 LAST PACK_TYPE 0402V
J 1
(-4975 1300);
DISPLAY 0.617021 (-4975 1300);
PAINT SKYBLUE (-4975 1300);
FORCEPROP 1 LAST VOLTAGE 25V
J 0
(-4975 1400);
DISPLAY 0.617021 (-4975 1400);
PAINT SKYBLUE (-4975 1400);
FORCEPROP 1 LAST MATERIAL X7R
J 0
(-4975 1350);
DISPLAY 0.617021 (-4975 1350);
PAINT SKYBLUE (-4975 1350);
FORCEPROP 1 LASTPIN (-5075 1500) $PN 1
J 0
(-5085 1515);
DISPLAY 0.617021 (-5085 1515);
PAINT ORANGE (-5085 1515);
FORCEPROP 1 LASTPIN (-4875 1500) $PN 2
J 0
(-4890 1515);
DISPLAY 0.617021 (-4890 1515);
PAINT ORANGE (-4890 1515);
FORCEPROP 1 LAST PART_NUMBER A36096-045
J 1
(-4975 1550);
DISPLAY 0.617021 (-4975 1550);
PAINT BLUE (-4975 1550);
FORCEPROP 1 LAST LOCATION C2L5
J 1
(-4975 1600);
DISPLAY 0.617021 (-4975 1600);
PAINT AQUA (-4975 1600);
FORCEPROP 2 LAST ROOM ST_SATA
J 0
(-5025 1650);
DISPLAY 1.361702 (-5025 1650);
PAINT ORANGE (-5025 1650);
DISPLAY INVISIBLE (-5025 1650);
FORCEPROP 2 LAST CDS_LOCATION C2L5
J 1
(-4975 1600);
DISPLAY 0.617021 (-4975 1600);
PAINT AQUA (-4975 1600);
DISPLAY INVISIBLE (-4975 1600);
FORCEPROP 2 LAST BOM_COST ST_SATA
J 0
(-5025 1600);
DISPLAY 1.361702 (-5025 1600);
PAINT ORANGE (-5025 1600);
DISPLAY INVISIBLE (-5025 1600);
FORCEPROP 2 LAST CDS_LIB dev_discrete
J 0
(-4975 1500);
PAINT ORANGE (-4975 1500);
DISPLAY INVISIBLE (-4975 1500);
FORCEPROP 2 LAST CDS_SEC 1
J 0
(-4975 1650);
PAINT ORANGE (-4975 1650);
DISPLAY INVISIBLE (-4975 1650);
FORCEPROP 2 LAST SEC_TYPE 0402V
J 0
(-4975 1750);
DISPLAY 1.021277 (-4975 1750);
PAINT ORANGE (-4975 1750);
DISPLAY INVISIBLE (-4975 1750);
FORCEPROP 2 LAST SEC 1
J 0
(-4975 1750);
DISPLAY 0.680851 (-4975 1750);
PAINT MONO (-4975 1750);
DISPLAY INVISIBLE (-4975 1750);
FORCEPROP 1 LAST PATH I209
J 0
(-4975 1700);
DISPLAY 0.978723 (-4975 1700);
PAINT WHITE (-4975 1700);
DISPLAY INVISIBLE (-4975 1700);
FORCEADD TAP..6
(-5250 2400);
FORCEPROP 3 LASTPIN (-5200 2400) SIG_NAME SATA6G_PCH_PCIE_UP_SATA_RXN<5>
J 0
(-5190 2410);
DISPLAY 0.659574 (-5190 2410);
PAINT MONO (-5190 2410);
DISPLAY INVISIBLE (-5190 2410);
FORCEPROP 1 LASTPIN (-5200 2400) BN 5
J 0
(-5252 2408);
DISPLAY 0.617021 (-5252 2408);
PAINT GREEN (-5252 2408);
FORCEPROP 2 LAST CDS_LIB mstr_standard
J 0
(-5250 2400);
PAINT ORANGE (-5250 2400);
DISPLAY INVISIBLE (-5250 2400);
FORCEPROP 1 LAST BODY_TYPE PLUMBING
J 0
(-5250 2350);
DISPLAY 0.872340 (-5250 2350);
PAINT GREEN (-5250 2350);
DISPLAY INVISIBLE (-5250 2350);
FORCEPROP 1 LAST HDL_TAP TRUE
J 0
(-4925 2275);
DISPLAY 0.872340 (-4925 2275);
PAINT ORANGE (-4925 2275);
DISPLAY INVISIBLE (-4925 2275);
FORCEPROP 1 LAST PATH I210
J 0
(-5252 2400);
DISPLAY 0.872340 (-5252 2400);
PAINT GREEN (-5252 2400);
DISPLAY INVISIBLE (-5252 2400);
FORCEADD TAP..6
(-5400 2050);
FORCEPROP 3 LASTPIN (-5350 2050) SIG_NAME SATA6G_PCH_PCIE_UP_SATA_RXP<6>
J 0
(-5340 2060);
DISPLAY 0.659574 (-5340 2060);
PAINT MONO (-5340 2060);
DISPLAY INVISIBLE (-5340 2060);
FORCEPROP 1 LASTPIN (-5350 2050) BN 6
J 0
(-5402 2058);
DISPLAY 0.617021 (-5402 2058);
PAINT GREEN (-5402 2058);
FORCEPROP 2 LAST CDS_LIB mstr_standard
J 0
(-5400 2050);
PAINT ORANGE (-5400 2050);
DISPLAY INVISIBLE (-5400 2050);
FORCEPROP 1 LAST BODY_TYPE PLUMBING
J 0
(-5400 2000);
DISPLAY 0.872340 (-5400 2000);
PAINT GREEN (-5400 2000);
DISPLAY INVISIBLE (-5400 2000);
FORCEPROP 1 LAST HDL_TAP TRUE
J 0
(-5075 1925);
DISPLAY 0.872340 (-5075 1925);
PAINT ORANGE (-5075 1925);
DISPLAY INVISIBLE (-5075 1925);
FORCEPROP 1 LAST PATH I211
J 0
(-5402 2050);
DISPLAY 0.872340 (-5402 2050);
PAINT GREEN (-5402 2050);
DISPLAY INVISIBLE (-5402 2050);
FORCEADD TAP..6
(-5400 1700);
FORCEPROP 3 LASTPIN (-5350 1700) SIG_NAME SATA6G_PCH_PCIE_UP_SATA_RXP<7>
J 0
(-5340 1710);
DISPLAY 0.659574 (-5340 1710);
PAINT MONO (-5340 1710);
DISPLAY INVISIBLE (-5340 1710);
FORCEPROP 1 LASTPIN (-5350 1700) BN 7
J 0
(-5402 1708);
DISPLAY 0.617021 (-5402 1708);
PAINT GREEN (-5402 1708);
FORCEPROP 1 LAST PATH I212
J 0
(-5402 1700);
DISPLAY 0.872340 (-5402 1700);
PAINT GREEN (-5402 1700);
DISPLAY INVISIBLE (-5402 1700);
FORCEPROP 1 LAST HDL_TAP TRUE
J 0
(-5075 1575);
DISPLAY 0.872340 (-5075 1575);
PAINT ORANGE (-5075 1575);
DISPLAY INVISIBLE (-5075 1575);
FORCEPROP 1 LAST BODY_TYPE PLUMBING
J 0
(-5400 1650);
DISPLAY 0.872340 (-5400 1650);
PAINT GREEN (-5400 1650);
DISPLAY INVISIBLE (-5400 1650);
FORCEPROP 2 LAST CDS_LIB mstr_standard
J 0
(-5400 1700);
PAINT ORANGE (-5400 1700);
DISPLAY INVISIBLE (-5400 1700);
FORCEADD TAP..6
(-5250 1850);
FORCEPROP 3 LASTPIN (-5200 1850) SIG_NAME SATA6G_PCH_PCIE_UP_SATA_RXN<6>
J 0
(-5190 1860);
DISPLAY 0.659574 (-5190 1860);
PAINT MONO (-5190 1860);
DISPLAY INVISIBLE (-5190 1860);
FORCEPROP 1 LASTPIN (-5200 1850) BN 6
J 0
(-5252 1858);
DISPLAY 0.617021 (-5252 1858);
PAINT GREEN (-5252 1858);
FORCEPROP 2 LAST CDS_LIB mstr_standard
J 0
(-5250 1850);
PAINT ORANGE (-5250 1850);
DISPLAY INVISIBLE (-5250 1850);
FORCEPROP 1 LAST BODY_TYPE PLUMBING
J 0
(-5250 1800);
DISPLAY 0.872340 (-5250 1800);
PAINT GREEN (-5250 1800);
DISPLAY INVISIBLE (-5250 1800);
FORCEPROP 1 LAST HDL_TAP TRUE
J 0
(-4925 1725);
DISPLAY 0.872340 (-4925 1725);
PAINT ORANGE (-4925 1725);
DISPLAY INVISIBLE (-4925 1725);
FORCEPROP 1 LAST PATH I213
J 0
(-5252 1850);
DISPLAY 0.872340 (-5252 1850);
PAINT GREEN (-5252 1850);
DISPLAY INVISIBLE (-5252 1850);
FORCEADD TAP..6
(-5250 1500);
FORCEPROP 3 LASTPIN (-5200 1500) SIG_NAME SATA6G_PCH_PCIE_UP_SATA_RXN<7>
J 0
(-5190 1510);
DISPLAY 0.659574 (-5190 1510);
PAINT MONO (-5190 1510);
DISPLAY INVISIBLE (-5190 1510);
FORCEPROP 1 LASTPIN (-5200 1500) BN 7
J 0
(-5252 1508);
DISPLAY 0.617021 (-5252 1508);
PAINT GREEN (-5252 1508);
FORCEPROP 2 LAST CDS_LIB mstr_standard
J 0
(-5250 1500);
PAINT ORANGE (-5250 1500);
DISPLAY INVISIBLE (-5250 1500);
FORCEPROP 1 LAST BODY_TYPE PLUMBING
J 0
(-5250 1450);
DISPLAY 0.872340 (-5250 1450);
PAINT GREEN (-5250 1450);
DISPLAY INVISIBLE (-5250 1450);
FORCEPROP 1 LAST HDL_TAP TRUE
J 0
(-4925 1375);
DISPLAY 0.872340 (-4925 1375);
PAINT ORANGE (-4925 1375);
DISPLAY INVISIBLE (-4925 1375);
FORCEPROP 1 LAST PATH I214
J 0
(-5252 1500);
DISPLAY 0.872340 (-5252 1500);
PAINT GREEN (-5252 1500);
DISPLAY INVISIBLE (-5252 1500);
FORCEADD TAP..1
(1300 1550);
FORCEPROP 3 LASTPIN (1250 1550) SIG_NAME SATA6G_PCH_PCIE_UP_SATA_TXN<7>
J 0
(1260 1560);
DISPLAY 0.659574 (1260 1560);
PAINT MONO (1260 1560);
DISPLAY INVISIBLE (1260 1560);
FORCEPROP 1 LASTPIN (1250 1550) BN 7
J 0
(1238 1558);
DISPLAY 0.617021 (1238 1558);
PAINT GREEN (1238 1558);
FORCEPROP 2 LAST CDS_LIB mstr_standard
J 0
(1300 1550);
PAINT ORANGE (1300 1550);
DISPLAY INVISIBLE (1300 1550);
FORCEPROP 1 LAST BODY_TYPE PLUMBING
J 0
(1300 1600);
DISPLAY 0.872340 (1300 1600);
PAINT GREEN (1300 1600);
DISPLAY INVISIBLE (1300 1600);
FORCEPROP 1 LAST HDL_TAP TRUE
J 0
(1625 1425);
DISPLAY 0.872340 (1625 1425);
PAINT ORANGE (1625 1425);
DISPLAY INVISIBLE (1625 1425);
FORCEPROP 1 LAST PATH I215
J 0
(1298 1550);
DISPLAY 0.872340 (1298 1550);
PAINT GREEN (1298 1550);
DISPLAY INVISIBLE (1298 1550);
FORCEADD TAP..1
(1450 4675);
FORCEPROP 3 LASTPIN (1400 4675) SIG_NAME SATA6G_PCH_PCIE_UP_SATA_TXP<0>
J 0
(1410 4685);
DISPLAY 0.659574 (1410 4685);
PAINT MONO (1410 4685);
DISPLAY INVISIBLE (1410 4685);
FORCEPROP 1 LASTPIN (1400 4675) BN 0
J 0
(1388 4683);
DISPLAY 0.617021 (1388 4683);
PAINT GREEN (1388 4683);
FORCEPROP 2 LAST CDS_LIB mstr_standard
J 0
(1450 4675);
PAINT ORANGE (1450 4675);
DISPLAY INVISIBLE (1450 4675);
FORCEPROP 1 LAST BODY_TYPE PLUMBING
J 0
(1450 4725);
DISPLAY 0.872340 (1450 4725);
PAINT GREEN (1450 4725);
DISPLAY INVISIBLE (1450 4725);
FORCEPROP 1 LAST HDL_TAP TRUE
J 0
(1775 4550);
DISPLAY 0.872340 (1775 4550);
PAINT ORANGE (1775 4550);
DISPLAY INVISIBLE (1775 4550);
FORCEPROP 1 LAST PATH I216
J 0
(1448 4675);
DISPLAY 0.872340 (1448 4675);
PAINT GREEN (1448 4675);
DISPLAY INVISIBLE (1448 4675);
FORCEADD TAP..1
(1450 4325);
FORCEPROP 3 LASTPIN (1400 4325) SIG_NAME SATA6G_PCH_PCIE_UP_SATA_TXP<1>
J 0
(1410 4335);
DISPLAY 0.659574 (1410 4335);
PAINT MONO (1410 4335);
DISPLAY INVISIBLE (1410 4335);
FORCEPROP 1 LASTPIN (1400 4325) BN 1
J 0
(1388 4333);
DISPLAY 0.617021 (1388 4333);
PAINT GREEN (1388 4333);
FORCEPROP 2 LAST CDS_LIB mstr_standard
J 0
(1450 4325);
PAINT ORANGE (1450 4325);
DISPLAY INVISIBLE (1450 4325);
FORCEPROP 1 LAST BODY_TYPE PLUMBING
J 0
(1450 4375);
DISPLAY 0.872340 (1450 4375);
PAINT GREEN (1450 4375);
DISPLAY INVISIBLE (1450 4375);
FORCEPROP 1 LAST HDL_TAP TRUE
J 0
(1775 4200);
DISPLAY 0.872340 (1775 4200);
PAINT ORANGE (1775 4200);
DISPLAY INVISIBLE (1775 4200);
FORCEPROP 1 LAST PATH I217
J 0
(1448 4325);
DISPLAY 0.872340 (1448 4325);
PAINT GREEN (1448 4325);
DISPLAY INVISIBLE (1448 4325);
FORCEADD TAP..1
(1300 4175);
FORCEPROP 3 LASTPIN (1250 4175) SIG_NAME SATA6G_PCH_PCIE_UP_SATA_TXN<1>
J 0
(1260 4185);
DISPLAY 0.659574 (1260 4185);
PAINT MONO (1260 4185);
DISPLAY INVISIBLE (1260 4185);
FORCEPROP 1 LASTPIN (1250 4175) BN 1
J 0
(1238 4183);
DISPLAY 0.617021 (1238 4183);
PAINT GREEN (1238 4183);
FORCEPROP 1 LAST PATH I218
J 0
(1298 4175);
DISPLAY 0.872340 (1298 4175);
PAINT GREEN (1298 4175);
DISPLAY INVISIBLE (1298 4175);
FORCEPROP 1 LAST HDL_TAP TRUE
J 0
(1625 4050);
DISPLAY 0.872340 (1625 4050);
PAINT ORANGE (1625 4050);
DISPLAY INVISIBLE (1625 4050);
FORCEPROP 1 LAST BODY_TYPE PLUMBING
J 0
(1300 4225);
DISPLAY 0.872340 (1300 4225);
PAINT GREEN (1300 4225);
DISPLAY INVISIBLE (1300 4225);
FORCEPROP 2 LAST CDS_LIB mstr_standard
J 0
(1300 4175);
PAINT ORANGE (1300 4175);
DISPLAY INVISIBLE (1300 4175);
FORCEADD TAP..1
(1300 4525);
FORCEPROP 3 LASTPIN (1250 4525) SIG_NAME SATA6G_PCH_PCIE_UP_SATA_TXN<0>
J 0
(1260 4535);
DISPLAY 0.659574 (1260 4535);
PAINT MONO (1260 4535);
DISPLAY INVISIBLE (1260 4535);
FORCEPROP 1 LASTPIN (1250 4525) BN 0
J 0
(1238 4533);
DISPLAY 0.617021 (1238 4533);
PAINT GREEN (1238 4533);
FORCEPROP 2 LAST CDS_LIB mstr_standard
J 0
(1300 4525);
PAINT ORANGE (1300 4525);
DISPLAY INVISIBLE (1300 4525);
FORCEPROP 1 LAST BODY_TYPE PLUMBING
J 0
(1300 4575);
DISPLAY 0.872340 (1300 4575);
PAINT GREEN (1300 4575);
DISPLAY INVISIBLE (1300 4575);
FORCEPROP 1 LAST HDL_TAP TRUE
J 0
(1625 4400);
DISPLAY 0.872340 (1625 4400);
PAINT ORANGE (1625 4400);
DISPLAY INVISIBLE (1625 4400);
FORCEPROP 1 LAST PATH I219
J 0
(1298 4525);
DISPLAY 0.872340 (1298 4525);
PAINT GREEN (1298 4525);
DISPLAY INVISIBLE (1298 4525);
FORCEADD CAP_A..2
(1025 4525);
FORCEPROP 1 LAST LOCATION C2L40
J 1
(1025 4625);
DISPLAY 0.617021 (1025 4625);
PAINT AQUA (1025 4625);
FORCEPROP 1 LAST PART_NUMBER A36096-045
J 1
(1025 4575);
DISPLAY 0.617021 (1025 4575);
PAINT BLUE (1025 4575);
FORCEPROP 1 LAST VALUE 0.01UF
J 2
(1025 4425);
DISPLAY 0.617021 (1025 4425);
PAINT SKYBLUE (1025 4425);
FORCEPROP 1 LAST TOLERANCE 10%
J 2
(1025 4375);
DISPLAY 0.617021 (1025 4375);
PAINT SKYBLUE (1025 4375);
FORCEPROP 1 LAST PACK_TYPE 0402V
J 1
(1025 4325);
DISPLAY 0.617021 (1025 4325);
PAINT SKYBLUE (1025 4325);
FORCEPROP 1 LAST VOLTAGE 25V
J 0
(1025 4425);
DISPLAY 0.617021 (1025 4425);
PAINT SKYBLUE (1025 4425);
FORCEPROP 1 LAST MATERIAL X7R
J 0
(1025 4375);
DISPLAY 0.617021 (1025 4375);
PAINT SKYBLUE (1025 4375);
FORCEPROP 1 LASTPIN (925 4525) $PN 1
J 0
(915 4540);
DISPLAY 0.617021 (915 4540);
PAINT ORANGE (915 4540);
FORCEPROP 1 LASTPIN (1125 4525) $PN 2
J 0
(1110 4540);
DISPLAY 0.617021 (1110 4540);
PAINT ORANGE (1110 4540);
FORCEPROP 2 LAST ROOM ST_SATA
J 0
(925 4675);
DISPLAY 1.361702 (925 4675);
PAINT ORANGE (925 4675);
DISPLAY INVISIBLE (925 4675);
FORCEPROP 2 LAST CDS_LOCATION C2L40
J 1
(1025 4625);
DISPLAY 0.617021 (1025 4625);
PAINT AQUA (1025 4625);
DISPLAY INVISIBLE (1025 4625);
FORCEPROP 2 LAST BOM_COST ST_SATA
J 0
(925 4675);
DISPLAY 1.361702 (925 4675);
PAINT ORANGE (925 4675);
DISPLAY INVISIBLE (925 4675);
FORCEPROP 2 LAST CDS_LIB dev_discrete
J 0
(1025 4525);
PAINT ORANGE (1025 4525);
DISPLAY INVISIBLE (1025 4525);
FORCEPROP 2 LAST CDS_SEC 1
J 0
(1025 4675);
PAINT ORANGE (1025 4675);
DISPLAY INVISIBLE (1025 4675);
FORCEPROP 2 LAST SEC_TYPE 0402V
J 0
(1025 4775);
DISPLAY 1.021277 (1025 4775);
PAINT ORANGE (1025 4775);
DISPLAY INVISIBLE (1025 4775);
FORCEPROP 2 LAST SEC 1
J 0
(1025 4775);
DISPLAY 0.680851 (1025 4775);
PAINT MONO (1025 4775);
DISPLAY INVISIBLE (1025 4775);
FORCEPROP 1 LAST PATH I220
J 0
(1025 4725);
DISPLAY 0.978723 (1025 4725);
PAINT WHITE (1025 4725);
DISPLAY INVISIBLE (1025 4725);
FORCEADD CAP_A..2
(650 4675);
FORCEPROP 1 LAST LOCATION C2L39
J 1
(650 4775);
DISPLAY 0.617021 (650 4775);
PAINT AQUA (650 4775);
FORCEPROP 1 LAST TOLERANCE 10%
J 2
(650 4525);
DISPLAY 0.617021 (650 4525);
PAINT SKYBLUE (650 4525);
FORCEPROP 1 LAST VOLTAGE 25V
J 0
(650 4575);
DISPLAY 0.617021 (650 4575);
PAINT SKYBLUE (650 4575);
FORCEPROP 1 LAST MATERIAL X7R
J 0
(650 4525);
DISPLAY 0.617021 (650 4525);
PAINT SKYBLUE (650 4525);
FORCEPROP 1 LASTPIN (550 4675) $PN 1
J 0
(540 4690);
DISPLAY 0.617021 (540 4690);
PAINT ORANGE (540 4690);
FORCEPROP 1 LASTPIN (750 4675) $PN 2
J 0
(735 4690);
DISPLAY 0.617021 (735 4690);
PAINT ORANGE (735 4690);
FORCEPROP 1 LAST PART_NUMBER A36096-045
J 1
(650 4725);
DISPLAY 0.617021 (650 4725);
PAINT BLUE (650 4725);
FORCEPROP 1 LAST VALUE 0.01UF
J 2
(650 4575);
DISPLAY 0.617021 (650 4575);
PAINT SKYBLUE (650 4575);
FORCEPROP 1 LAST PACK_TYPE 0402V
J 1
(650 4475);
DISPLAY 0.617021 (650 4475);
PAINT SKYBLUE (650 4475);
FORCEPROP 2 LAST ROOM ST_SATA
J 0
(600 4825);
DISPLAY 1.361702 (600 4825);
PAINT ORANGE (600 4825);
DISPLAY INVISIBLE (600 4825);
FORCEPROP 2 LAST CDS_LOCATION C2L39
J 1
(650 4775);
DISPLAY 0.617021 (650 4775);
PAINT AQUA (650 4775);
DISPLAY INVISIBLE (650 4775);
FORCEPROP 2 LAST BOM_COST ST_SATA
J 0
(600 4825);
DISPLAY 1.361702 (600 4825);
PAINT ORANGE (600 4825);
DISPLAY INVISIBLE (600 4825);
FORCEPROP 2 LAST CDS_LIB dev_discrete
J 0
(650 4675);
PAINT ORANGE (650 4675);
DISPLAY INVISIBLE (650 4675);
FORCEPROP 2 LAST CDS_SEC 1
J 0
(650 4825);
PAINT ORANGE (650 4825);
DISPLAY INVISIBLE (650 4825);
FORCEPROP 2 LAST SEC_TYPE 0402V
J 0
(650 4925);
DISPLAY 1.021277 (650 4925);
PAINT ORANGE (650 4925);
DISPLAY INVISIBLE (650 4925);
FORCEPROP 2 LAST SEC 1
J 0
(650 4925);
DISPLAY 0.680851 (650 4925);
PAINT MONO (650 4925);
DISPLAY INVISIBLE (650 4925);
FORCEPROP 1 LAST PATH I221
J 0
(650 4875);
DISPLAY 0.978723 (650 4875);
PAINT WHITE (650 4875);
DISPLAY INVISIBLE (650 4875);
FORCEADD CAP_A..2
(650 4325);
FORCEPROP 1 LAST TOLERANCE 10%
J 2
(650 4175);
DISPLAY 0.617021 (650 4175);
PAINT SKYBLUE (650 4175);
FORCEPROP 1 LAST PACK_TYPE 0402V
J 1
(650 4125);
DISPLAY 0.617021 (650 4125);
PAINT SKYBLUE (650 4125);
FORCEPROP 1 LAST MATERIAL X7R
J 0
(650 4175);
DISPLAY 0.617021 (650 4175);
PAINT SKYBLUE (650 4175);
FORCEPROP 1 LASTPIN (750 4325) $PN 2
J 0
(735 4340);
DISPLAY 0.617021 (735 4340);
PAINT ORANGE (735 4340);
FORCEPROP 1 LASTPIN (550 4325) $PN 1
J 0
(540 4340);
DISPLAY 0.617021 (540 4340);
PAINT ORANGE (540 4340);
FORCEPROP 1 LAST VOLTAGE 25V
J 0
(650 4225);
DISPLAY 0.617021 (650 4225);
PAINT SKYBLUE (650 4225);
FORCEPROP 1 LAST VALUE 0.01UF
J 2
(650 4225);
DISPLAY 0.617021 (650 4225);
PAINT SKYBLUE (650 4225);
FORCEPROP 1 LAST PART_NUMBER A36096-045
J 1
(650 4375);
DISPLAY 0.617021 (650 4375);
PAINT BLUE (650 4375);
FORCEPROP 1 LAST LOCATION C2L43
J 1
(650 4425);
DISPLAY 0.617021 (650 4425);
PAINT AQUA (650 4425);
FORCEPROP 2 LAST ROOM ST_SATA
J 0
(550 4475);
DISPLAY 1.361702 (550 4475);
PAINT ORANGE (550 4475);
DISPLAY INVISIBLE (550 4475);
FORCEPROP 2 LAST CDS_LOCATION C2L43
J 1
(650 4425);
DISPLAY 0.617021 (650 4425);
PAINT AQUA (650 4425);
DISPLAY INVISIBLE (650 4425);
FORCEPROP 2 LAST BOM_COST ST_SATA
J 0
(550 4475);
DISPLAY 1.361702 (550 4475);
PAINT ORANGE (550 4475);
DISPLAY INVISIBLE (550 4475);
FORCEPROP 2 LAST CDS_LIB dev_discrete
J 0
(650 4325);
PAINT ORANGE (650 4325);
DISPLAY INVISIBLE (650 4325);
FORCEPROP 2 LAST CDS_SEC 1
J 0
(650 4475);
PAINT ORANGE (650 4475);
DISPLAY INVISIBLE (650 4475);
FORCEPROP 2 LAST SEC_TYPE 0402V
J 0
(650 4575);
DISPLAY 1.021277 (650 4575);
PAINT ORANGE (650 4575);
DISPLAY INVISIBLE (650 4575);
FORCEPROP 2 LAST SEC 1
J 0
(650 4575);
DISPLAY 0.680851 (650 4575);
PAINT MONO (650 4575);
DISPLAY INVISIBLE (650 4575);
FORCEPROP 1 LAST PATH I222
J 0
(650 4525);
DISPLAY 0.978723 (650 4525);
PAINT WHITE (650 4525);
DISPLAY INVISIBLE (650 4525);
FORCEADD OFFPAGE..1
(25 5225);
FORCEPROP 2 LAST $XR0 116 
J 0
(-227 5225);
DISPLAY 0.638298 (-227 5225);
PAINT MONO (-227 5225);
FORCEPROP 2 LAST CDS_LIB mstr_standard
J 0
(25 5225);
PAINT ORANGE (25 5225);
DISPLAY INVISIBLE (25 5225);
FORCEPROP 1 LAST OFFPAGE TRUE
J 0
(350 5100);
DISPLAY 0.872340 (350 5100);
PAINT GREEN (350 5100);
DISPLAY INVISIBLE (350 5100);
FORCEPROP 1 LAST COMMENT_BODY TRUE
J 0
(150 5125);
DISPLAY 0.872340 (150 5125);
PAINT GREEN (150 5125);
DISPLAY INVISIBLE (150 5125);
FORCEPROP 2 LAST PATH I223
J 0
(-225 5275);
DISPLAY 1.021277 (-225 5275);
PAINT ORANGE (-225 5275);
DISPLAY INVISIBLE (-225 5275);
FORCEADD OFFPAGE..1
(25 5075);
FORCEPROP 2 LAST $XR0 116 
J 0
(-227 5075);
DISPLAY 0.638298 (-227 5075);
PAINT MONO (-227 5075);
FORCEPROP 2 LAST CDS_LIB mstr_standard
J 0
(25 5075);
PAINT ORANGE (25 5075);
DISPLAY INVISIBLE (25 5075);
FORCEPROP 1 LAST OFFPAGE TRUE
J 0
(350 4950);
DISPLAY 0.872340 (350 4950);
PAINT GREEN (350 4950);
DISPLAY INVISIBLE (350 4950);
FORCEPROP 1 LAST COMMENT_BODY TRUE
J 0
(150 4975);
DISPLAY 0.872340 (150 4975);
PAINT GREEN (150 4975);
DISPLAY INVISIBLE (150 4975);
FORCEPROP 2 LAST PATH I224
J 0
(-225 5125);
DISPLAY 1.021277 (-225 5125);
PAINT ORANGE (-225 5125);
DISPLAY INVISIBLE (-225 5125);
FORCEADD CAP_A..2
(1025 4175);
FORCEPROP 1 LAST LOCATION C2L44
J 1
(1025 4275);
DISPLAY 0.617021 (1025 4275);
PAINT AQUA (1025 4275);
FORCEPROP 1 LAST PART_NUMBER A36096-045
J 1
(1025 4225);
DISPLAY 0.617021 (1025 4225);
PAINT BLUE (1025 4225);
FORCEPROP 1 LAST VALUE 0.01UF
J 2
(1025 4075);
DISPLAY 0.617021 (1025 4075);
PAINT SKYBLUE (1025 4075);
FORCEPROP 1 LAST TOLERANCE 10%
J 2
(1025 4025);
DISPLAY 0.617021 (1025 4025);
PAINT SKYBLUE (1025 4025);
FORCEPROP 1 LAST PACK_TYPE 0402V
J 1
(1025 3975);
DISPLAY 0.617021 (1025 3975);
PAINT SKYBLUE (1025 3975);
FORCEPROP 1 LAST VOLTAGE 25V
J 0
(1025 4075);
DISPLAY 0.617021 (1025 4075);
PAINT SKYBLUE (1025 4075);
FORCEPROP 1 LAST MATERIAL X7R
J 0
(1025 4025);
DISPLAY 0.617021 (1025 4025);
PAINT SKYBLUE (1025 4025);
FORCEPROP 1 LASTPIN (1125 4175) $PN 2
J 0
(1110 4190);
DISPLAY 0.617021 (1110 4190);
PAINT ORANGE (1110 4190);
FORCEPROP 1 LASTPIN (925 4175) $PN 1
J 0
(915 4190);
DISPLAY 0.617021 (915 4190);
PAINT ORANGE (915 4190);
FORCEPROP 2 LAST ROOM ST_SATA
J 0
(925 4325);
DISPLAY 1.361702 (925 4325);
PAINT ORANGE (925 4325);
DISPLAY INVISIBLE (925 4325);
FORCEPROP 1 LAST PATH I228
J 0
(1025 4375);
DISPLAY 0.978723 (1025 4375);
PAINT WHITE (1025 4375);
DISPLAY INVISIBLE (1025 4375);
FORCEPROP 2 LAST SEC 1
J 0
(1025 4425);
DISPLAY 0.680851 (1025 4425);
PAINT MONO (1025 4425);
DISPLAY INVISIBLE (1025 4425);
FORCEPROP 2 LAST SEC_TYPE 0402V
J 0
(1025 4425);
DISPLAY 1.021277 (1025 4425);
PAINT ORANGE (1025 4425);
DISPLAY INVISIBLE (1025 4425);
FORCEPROP 2 LAST CDS_SEC 1
J 0
(1025 4325);
PAINT ORANGE (1025 4325);
DISPLAY INVISIBLE (1025 4325);
FORCEPROP 2 LAST CDS_LIB dev_discrete
J 0
(1025 4175);
PAINT ORANGE (1025 4175);
DISPLAY INVISIBLE (1025 4175);
FORCEPROP 2 LAST BOM_COST ST_SATA
J 0
(925 4325);
DISPLAY 1.361702 (925 4325);
PAINT ORANGE (925 4325);
DISPLAY INVISIBLE (925 4325);
FORCEPROP 2 LAST CDS_LOCATION C2L44
J 1
(1025 4275);
DISPLAY 0.617021 (1025 4275);
PAINT AQUA (1025 4275);
DISPLAY INVISIBLE (1025 4275);
FORCEADD TAP..1
(1450 3650);
FORCEPROP 3 LASTPIN (1400 3650) SIG_NAME SATA6G_PCH_PCIE_UP_SATA_TXP<2>
J 0
(1410 3660);
DISPLAY 0.659574 (1410 3660);
PAINT MONO (1410 3660);
DISPLAY INVISIBLE (1410 3660);
FORCEPROP 1 LASTPIN (1400 3650) BN 2
J 0
(1388 3658);
DISPLAY 0.617021 (1388 3658);
PAINT GREEN (1388 3658);
FORCEPROP 1 LAST PATH I229
J 0
(1448 3650);
DISPLAY 0.872340 (1448 3650);
PAINT GREEN (1448 3650);
DISPLAY INVISIBLE (1448 3650);
FORCEPROP 1 LAST HDL_TAP TRUE
J 0
(1775 3525);
DISPLAY 0.872340 (1775 3525);
PAINT ORANGE (1775 3525);
DISPLAY INVISIBLE (1775 3525);
FORCEPROP 1 LAST BODY_TYPE PLUMBING
J 0
(1450 3700);
DISPLAY 0.872340 (1450 3700);
PAINT GREEN (1450 3700);
DISPLAY INVISIBLE (1450 3700);
FORCEPROP 2 LAST CDS_LIB mstr_standard
J 0
(1450 3650);
PAINT ORANGE (1450 3650);
DISPLAY INVISIBLE (1450 3650);
FORCEADD TAP..1
(1450 3300);
FORCEPROP 3 LASTPIN (1400 3300) SIG_NAME SATA6G_PCH_PCIE_UP_SATA_TXP<3>
J 0
(1410 3310);
DISPLAY 0.659574 (1410 3310);
PAINT MONO (1410 3310);
DISPLAY INVISIBLE (1410 3310);
FORCEPROP 1 LASTPIN (1400 3300) BN 3
J 0
(1388 3308);
DISPLAY 0.617021 (1388 3308);
PAINT GREEN (1388 3308);
FORCEPROP 1 LAST PATH I230
J 0
(1448 3300);
DISPLAY 0.872340 (1448 3300);
PAINT GREEN (1448 3300);
DISPLAY INVISIBLE (1448 3300);
FORCEPROP 1 LAST HDL_TAP TRUE
J 0
(1775 3175);
DISPLAY 0.872340 (1775 3175);
PAINT ORANGE (1775 3175);
DISPLAY INVISIBLE (1775 3175);
FORCEPROP 1 LAST BODY_TYPE PLUMBING
J 0
(1450 3350);
DISPLAY 0.872340 (1450 3350);
PAINT GREEN (1450 3350);
DISPLAY INVISIBLE (1450 3350);
FORCEPROP 2 LAST CDS_LIB mstr_standard
J 0
(1450 3300);
PAINT ORANGE (1450 3300);
DISPLAY INVISIBLE (1450 3300);
FORCEADD TAP..1
(1300 3500);
FORCEPROP 3 LASTPIN (1250 3500) SIG_NAME SATA6G_PCH_PCIE_UP_SATA_TXN<2>
J 0
(1260 3510);
DISPLAY 0.659574 (1260 3510);
PAINT MONO (1260 3510);
DISPLAY INVISIBLE (1260 3510);
FORCEPROP 1 LASTPIN (1250 3500) BN 2
J 0
(1238 3508);
DISPLAY 0.617021 (1238 3508);
PAINT GREEN (1238 3508);
FORCEPROP 1 LAST PATH I231
J 0
(1298 3500);
DISPLAY 0.872340 (1298 3500);
PAINT GREEN (1298 3500);
DISPLAY INVISIBLE (1298 3500);
FORCEPROP 1 LAST HDL_TAP TRUE
J 0
(1625 3375);
DISPLAY 0.872340 (1625 3375);
PAINT ORANGE (1625 3375);
DISPLAY INVISIBLE (1625 3375);
FORCEPROP 1 LAST BODY_TYPE PLUMBING
J 0
(1300 3550);
DISPLAY 0.872340 (1300 3550);
PAINT GREEN (1300 3550);
DISPLAY INVISIBLE (1300 3550);
FORCEPROP 2 LAST CDS_LIB mstr_standard
J 0
(1300 3500);
PAINT ORANGE (1300 3500);
DISPLAY INVISIBLE (1300 3500);
FORCEADD TAP..1
(1300 3075);
FORCEPROP 3 LASTPIN (1250 3075) SIG_NAME SATA6G_PCH_PCIE_UP_SATA_TXN<3>
J 0
(1260 3085);
DISPLAY 0.659574 (1260 3085);
PAINT MONO (1260 3085);
DISPLAY INVISIBLE (1260 3085);
FORCEPROP 1 LASTPIN (1250 3075) BN 3
J 0
(1238 3083);
DISPLAY 0.617021 (1238 3083);
PAINT GREEN (1238 3083);
FORCEPROP 1 LAST PATH I232
J 0
(1298 3075);
DISPLAY 0.872340 (1298 3075);
PAINT GREEN (1298 3075);
DISPLAY INVISIBLE (1298 3075);
FORCEPROP 1 LAST HDL_TAP TRUE
J 0
(1625 2950);
DISPLAY 0.872340 (1625 2950);
PAINT ORANGE (1625 2950);
DISPLAY INVISIBLE (1625 2950);
FORCEPROP 1 LAST BODY_TYPE PLUMBING
J 0
(1300 3125);
DISPLAY 0.872340 (1300 3125);
PAINT GREEN (1300 3125);
DISPLAY INVISIBLE (1300 3125);
FORCEPROP 2 LAST CDS_LIB mstr_standard
J 0
(1300 3075);
PAINT ORANGE (1300 3075);
DISPLAY INVISIBLE (1300 3075);
FORCEADD CAP_A..2
(1000 3500);
FORCEPROP 1 LAST LOCATION C2L42
J 1
(1000 3600);
DISPLAY 0.617021 (1000 3600);
PAINT AQUA (1000 3600);
FORCEPROP 1 LAST VALUE 0.01UF
J 2
(1000 3400);
DISPLAY 0.617021 (1000 3400);
PAINT SKYBLUE (1000 3400);
FORCEPROP 1 LAST TOLERANCE 10%
J 2
(1000 3350);
DISPLAY 0.617021 (1000 3350);
PAINT SKYBLUE (1000 3350);
FORCEPROP 1 LAST PACK_TYPE 0402V
J 1
(1000 3300);
DISPLAY 0.617021 (1000 3300);
PAINT SKYBLUE (1000 3300);
FORCEPROP 1 LAST VOLTAGE 25V
J 0
(1000 3400);
DISPLAY 0.617021 (1000 3400);
PAINT SKYBLUE (1000 3400);
FORCEPROP 1 LAST MATERIAL X7R
J 0
(1000 3350);
DISPLAY 0.617021 (1000 3350);
PAINT SKYBLUE (1000 3350);
FORCEPROP 1 LASTPIN (900 3500) $PN 1
J 0
(890 3515);
DISPLAY 0.617021 (890 3515);
PAINT ORANGE (890 3515);
FORCEPROP 1 LASTPIN (1100 3500) $PN 2
J 0
(1085 3515);
DISPLAY 0.617021 (1085 3515);
PAINT ORANGE (1085 3515);
FORCEPROP 1 LAST PART_NUMBER A36096-045
J 1
(1000 3550);
DISPLAY 0.617021 (1000 3550);
PAINT BLUE (1000 3550);
FORCEPROP 2 LAST ROOM ST_SATA
J 0
(925 3650);
DISPLAY 1.361702 (925 3650);
PAINT ORANGE (925 3650);
DISPLAY INVISIBLE (925 3650);
FORCEPROP 2 LAST CDS_LOCATION C2L42
J 1
(1000 3600);
DISPLAY 0.617021 (1000 3600);
PAINT AQUA (1000 3600);
DISPLAY INVISIBLE (1000 3600);
FORCEPROP 2 LAST BOM_COST ST_SATA
J 0
(925 3650);
DISPLAY 1.361702 (925 3650);
PAINT ORANGE (925 3650);
DISPLAY INVISIBLE (925 3650);
FORCEPROP 2 LAST CDS_LIB dev_discrete
J 0
(1000 3500);
PAINT ORANGE (1000 3500);
DISPLAY INVISIBLE (1000 3500);
FORCEPROP 2 LAST CDS_SEC 1
J 0
(1000 3650);
PAINT ORANGE (1000 3650);
DISPLAY INVISIBLE (1000 3650);
FORCEPROP 2 LAST SEC_TYPE 0402V
J 0
(1000 3750);
DISPLAY 1.021277 (1000 3750);
PAINT ORANGE (1000 3750);
DISPLAY INVISIBLE (1000 3750);
FORCEPROP 2 LAST SEC 1
J 0
(1000 3750);
DISPLAY 0.680851 (1000 3750);
PAINT MONO (1000 3750);
DISPLAY INVISIBLE (1000 3750);
FORCEPROP 1 LAST PATH I233
J 0
(1000 3700);
DISPLAY 0.978723 (1000 3700);
PAINT WHITE (1000 3700);
DISPLAY INVISIBLE (1000 3700);
FORCEADD CAP_A..2
(1025 3075);
FORCEPROP 1 LAST LOCATION C2L22
J 1
(1025 3175);
DISPLAY 0.617021 (1025 3175);
PAINT AQUA (1025 3175);
FORCEPROP 1 LAST PART_NUMBER A36096-045
J 1
(1025 3125);
DISPLAY 0.617021 (1025 3125);
PAINT BLUE (1025 3125);
FORCEPROP 1 LAST VALUE 0.01UF
J 2
(1025 2975);
DISPLAY 0.617021 (1025 2975);
PAINT SKYBLUE (1025 2975);
FORCEPROP 1 LAST TOLERANCE 10%
J 2
(1025 2925);
DISPLAY 0.617021 (1025 2925);
PAINT SKYBLUE (1025 2925);
FORCEPROP 1 LAST PACK_TYPE 0402V
J 1
(1025 2875);
DISPLAY 0.617021 (1025 2875);
PAINT SKYBLUE (1025 2875);
FORCEPROP 1 LAST VOLTAGE 25V
J 0
(1025 2975);
DISPLAY 0.617021 (1025 2975);
PAINT SKYBLUE (1025 2975);
FORCEPROP 1 LAST MATERIAL X7R
J 0
(1025 2925);
DISPLAY 0.617021 (1025 2925);
PAINT SKYBLUE (1025 2925);
FORCEPROP 1 LASTPIN (925 3075) $PN 1
J 0
(915 3090);
DISPLAY 0.617021 (915 3090);
PAINT ORANGE (915 3090);
FORCEPROP 1 LASTPIN (1125 3075) $PN 2
J 0
(1110 3090);
DISPLAY 0.617021 (1110 3090);
PAINT ORANGE (1110 3090);
FORCEPROP 2 LAST ROOM ST_SATA
J 0
(950 3225);
DISPLAY 1.361702 (950 3225);
PAINT ORANGE (950 3225);
DISPLAY INVISIBLE (950 3225);
FORCEPROP 2 LAST CDS_LOCATION C2L22
J 1
(1025 3175);
DISPLAY 0.617021 (1025 3175);
PAINT AQUA (1025 3175);
DISPLAY INVISIBLE (1025 3175);
FORCEPROP 2 LAST BOM_COST ST_SATA
J 0
(950 3225);
DISPLAY 1.361702 (950 3225);
PAINT ORANGE (950 3225);
DISPLAY INVISIBLE (950 3225);
FORCEPROP 2 LAST CDS_LIB dev_discrete
J 0
(1025 3075);
PAINT ORANGE (1025 3075);
DISPLAY INVISIBLE (1025 3075);
FORCEPROP 2 LAST CDS_SEC 1
J 0
(1025 3225);
PAINT ORANGE (1025 3225);
DISPLAY INVISIBLE (1025 3225);
FORCEPROP 2 LAST SEC_TYPE 0402V
J 0
(1025 3325);
DISPLAY 1.021277 (1025 3325);
PAINT ORANGE (1025 3325);
DISPLAY INVISIBLE (1025 3325);
FORCEPROP 2 LAST SEC 1
J 0
(1025 3325);
DISPLAY 0.680851 (1025 3325);
PAINT MONO (1025 3325);
DISPLAY INVISIBLE (1025 3325);
FORCEPROP 1 LAST PATH I234
J 0
(1025 3275);
DISPLAY 0.978723 (1025 3275);
PAINT WHITE (1025 3275);
DISPLAY INVISIBLE (1025 3275);
FORCEADD TAP..1
(1450 2925);
FORCEPROP 3 LASTPIN (1400 2925) SIG_NAME SATA6G_PCH_PCIE_UP_SATA_TXP<4>
J 0
(1410 2935);
DISPLAY 0.659574 (1410 2935);
PAINT MONO (1410 2935);
DISPLAY INVISIBLE (1410 2935);
FORCEPROP 1 LASTPIN (1400 2925) BN 4
J 0
(1388 2933);
DISPLAY 0.617021 (1388 2933);
PAINT GREEN (1388 2933);
FORCEPROP 1 LAST PATH I235
J 0
(1448 2925);
DISPLAY 0.872340 (1448 2925);
PAINT GREEN (1448 2925);
DISPLAY INVISIBLE (1448 2925);
FORCEPROP 1 LAST HDL_TAP TRUE
J 0
(1775 2800);
DISPLAY 0.872340 (1775 2800);
PAINT ORANGE (1775 2800);
DISPLAY INVISIBLE (1775 2800);
FORCEPROP 1 LAST BODY_TYPE PLUMBING
J 0
(1450 2975);
DISPLAY 0.872340 (1450 2975);
PAINT GREEN (1450 2975);
DISPLAY INVISIBLE (1450 2975);
FORCEPROP 2 LAST CDS_LIB mstr_standard
J 0
(1450 2925);
PAINT ORANGE (1450 2925);
DISPLAY INVISIBLE (1450 2925);
FORCEADD TAP..1
(1450 2500);
FORCEPROP 3 LASTPIN (1400 2500) SIG_NAME SATA6G_PCH_PCIE_UP_SATA_TXP<5>
J 0
(1410 2510);
DISPLAY 0.659574 (1410 2510);
PAINT MONO (1410 2510);
DISPLAY INVISIBLE (1410 2510);
FORCEPROP 1 LASTPIN (1400 2500) BN 5
J 0
(1388 2508);
DISPLAY 0.617021 (1388 2508);
PAINT GREEN (1388 2508);
FORCEPROP 1 LAST PATH I236
J 0
(1448 2500);
DISPLAY 0.872340 (1448 2500);
PAINT GREEN (1448 2500);
DISPLAY INVISIBLE (1448 2500);
FORCEPROP 1 LAST HDL_TAP TRUE
J 0
(1775 2375);
DISPLAY 0.872340 (1775 2375);
PAINT ORANGE (1775 2375);
DISPLAY INVISIBLE (1775 2375);
FORCEPROP 1 LAST BODY_TYPE PLUMBING
J 0
(1450 2550);
DISPLAY 0.872340 (1450 2550);
PAINT GREEN (1450 2550);
DISPLAY INVISIBLE (1450 2550);
FORCEPROP 2 LAST CDS_LIB mstr_standard
J 0
(1450 2500);
PAINT ORANGE (1450 2500);
DISPLAY INVISIBLE (1450 2500);
FORCEADD TAP..1
(1300 2725);
FORCEPROP 3 LASTPIN (1250 2725) SIG_NAME SATA6G_PCH_PCIE_UP_SATA_TXN<4>
J 0
(1260 2735);
DISPLAY 0.659574 (1260 2735);
PAINT MONO (1260 2735);
DISPLAY INVISIBLE (1260 2735);
FORCEPROP 1 LASTPIN (1250 2725) BN 4
J 0
(1238 2733);
DISPLAY 0.617021 (1238 2733);
PAINT GREEN (1238 2733);
FORCEPROP 2 LAST CDS_LIB mstr_standard
J 0
(1300 2725);
PAINT ORANGE (1300 2725);
DISPLAY INVISIBLE (1300 2725);
FORCEPROP 1 LAST BODY_TYPE PLUMBING
J 0
(1300 2775);
DISPLAY 0.872340 (1300 2775);
PAINT GREEN (1300 2775);
DISPLAY INVISIBLE (1300 2775);
FORCEPROP 1 LAST HDL_TAP TRUE
J 0
(1625 2600);
DISPLAY 0.872340 (1625 2600);
PAINT ORANGE (1625 2600);
DISPLAY INVISIBLE (1625 2600);
FORCEPROP 1 LAST PATH I237
J 0
(1298 2725);
DISPLAY 0.872340 (1298 2725);
PAINT GREEN (1298 2725);
DISPLAY INVISIBLE (1298 2725);
FORCEADD CAP_A..2
(1025 2725);
FORCEPROP 1 LAST LOCATION C2L37
J 1
(1025 2825);
DISPLAY 0.617021 (1025 2825);
PAINT AQUA (1025 2825);
FORCEPROP 1 LAST PART_NUMBER A36096-045
J 1
(1025 2775);
DISPLAY 0.617021 (1025 2775);
PAINT BLUE (1025 2775);
FORCEPROP 1 LAST VALUE 0.01UF
J 2
(1025 2625);
DISPLAY 0.617021 (1025 2625);
PAINT SKYBLUE (1025 2625);
FORCEPROP 1 LAST TOLERANCE 10%
J 2
(1025 2575);
DISPLAY 0.617021 (1025 2575);
PAINT SKYBLUE (1025 2575);
FORCEPROP 1 LAST PACK_TYPE 0402V
J 1
(1025 2525);
DISPLAY 0.617021 (1025 2525);
PAINT SKYBLUE (1025 2525);
FORCEPROP 1 LAST VOLTAGE 25V
J 0
(1025 2625);
DISPLAY 0.617021 (1025 2625);
PAINT SKYBLUE (1025 2625);
FORCEPROP 1 LAST MATERIAL X7R
J 0
(1025 2575);
DISPLAY 0.617021 (1025 2575);
PAINT SKYBLUE (1025 2575);
FORCEPROP 1 LASTPIN (925 2725) $PN 1
J 0
(915 2740);
DISPLAY 0.617021 (915 2740);
PAINT ORANGE (915 2740);
FORCEPROP 1 LASTPIN (1125 2725) $PN 2
J 0
(1110 2740);
DISPLAY 0.617021 (1110 2740);
PAINT ORANGE (1110 2740);
FORCEPROP 2 LAST ROOM ST_SATA
J 0
(975 2875);
DISPLAY 1.361702 (975 2875);
PAINT ORANGE (975 2875);
DISPLAY INVISIBLE (975 2875);
FORCEPROP 2 LAST CDS_LOCATION C2L37
J 1
(1025 2825);
DISPLAY 0.617021 (1025 2825);
PAINT AQUA (1025 2825);
DISPLAY INVISIBLE (1025 2825);
FORCEPROP 2 LAST BOM_COST ST_SATA
J 0
(975 2875);
DISPLAY 1.361702 (975 2875);
PAINT ORANGE (975 2875);
DISPLAY INVISIBLE (975 2875);
FORCEPROP 2 LAST CDS_LIB dev_discrete
J 0
(1025 2725);
PAINT ORANGE (1025 2725);
DISPLAY INVISIBLE (1025 2725);
FORCEPROP 2 LAST CDS_SEC 1
J 0
(1025 2875);
PAINT ORANGE (1025 2875);
DISPLAY INVISIBLE (1025 2875);
FORCEPROP 2 LAST SEC_TYPE 0402V
J 0
(1025 2975);
DISPLAY 1.021277 (1025 2975);
PAINT ORANGE (1025 2975);
DISPLAY INVISIBLE (1025 2975);
FORCEPROP 2 LAST SEC 1
J 0
(1025 2975);
DISPLAY 0.680851 (1025 2975);
PAINT MONO (1025 2975);
DISPLAY INVISIBLE (1025 2975);
FORCEPROP 1 LAST PATH I238
J 0
(1025 2925);
DISPLAY 0.978723 (1025 2925);
PAINT WHITE (1025 2925);
DISPLAY INVISIBLE (1025 2925);
FORCEADD CAP_A..2
(650 2925);
FORCEPROP 1 LAST LOCATION C2L47
J 1
(650 3025);
DISPLAY 0.617021 (650 3025);
PAINT AQUA (650 3025);
FORCEPROP 1 LAST PART_NUMBER A36096-045
J 1
(650 2975);
DISPLAY 0.617021 (650 2975);
PAINT BLUE (650 2975);
FORCEPROP 1 LAST VALUE 0.01UF
J 2
(650 2825);
DISPLAY 0.617021 (650 2825);
PAINT SKYBLUE (650 2825);
FORCEPROP 1 LAST TOLERANCE 10%
J 2
(650 2775);
DISPLAY 0.617021 (650 2775);
PAINT SKYBLUE (650 2775);
FORCEPROP 1 LAST PACK_TYPE 0402V
J 1
(650 2725);
DISPLAY 0.617021 (650 2725);
PAINT SKYBLUE (650 2725);
FORCEPROP 1 LAST VOLTAGE 25V
J 0
(650 2825);
DISPLAY 0.617021 (650 2825);
PAINT SKYBLUE (650 2825);
FORCEPROP 1 LAST MATERIAL X7R
J 0
(650 2775);
DISPLAY 0.617021 (650 2775);
PAINT SKYBLUE (650 2775);
FORCEPROP 1 LASTPIN (750 2925) $PN 2
J 0
(735 2940);
DISPLAY 0.617021 (735 2940);
PAINT ORANGE (735 2940);
FORCEPROP 1 LASTPIN (550 2925) $PN 1
J 0
(540 2940);
DISPLAY 0.617021 (540 2940);
PAINT ORANGE (540 2940);
FORCEPROP 2 LAST ROOM ST_SATA
J 0
(600 3075);
DISPLAY 1.361702 (600 3075);
PAINT ORANGE (600 3075);
DISPLAY INVISIBLE (600 3075);
FORCEPROP 1 LAST PATH I239
J 0
(650 3125);
DISPLAY 0.978723 (650 3125);
PAINT WHITE (650 3125);
DISPLAY INVISIBLE (650 3125);
FORCEPROP 2 LAST SEC 1
J 0
(650 3175);
DISPLAY 0.680851 (650 3175);
PAINT MONO (650 3175);
DISPLAY INVISIBLE (650 3175);
FORCEPROP 2 LAST SEC_TYPE 0402V
J 0
(650 3175);
DISPLAY 1.021277 (650 3175);
PAINT ORANGE (650 3175);
DISPLAY INVISIBLE (650 3175);
FORCEPROP 2 LAST CDS_SEC 1
J 0
(650 3075);
PAINT ORANGE (650 3075);
DISPLAY INVISIBLE (650 3075);
FORCEPROP 2 LAST CDS_LIB dev_discrete
J 0
(650 2925);
PAINT ORANGE (650 2925);
DISPLAY INVISIBLE (650 2925);
FORCEPROP 2 LAST BOM_COST ST_SATA
J 0
(600 3075);
DISPLAY 1.361702 (600 3075);
PAINT ORANGE (600 3075);
DISPLAY INVISIBLE (600 3075);
FORCEPROP 2 LAST CDS_LOCATION C2L47
J 1
(650 3025);
DISPLAY 0.617021 (650 3025);
PAINT AQUA (650 3025);
DISPLAY INVISIBLE (650 3025);
FORCEADD CAP_A..2
(650 2500);
FORCEPROP 1 LAST LOCATION C2L27
J 1
(650 2600);
DISPLAY 0.617021 (650 2600);
PAINT AQUA (650 2600);
FORCEPROP 1 LAST TOLERANCE 10%
J 2
(650 2350);
DISPLAY 0.617021 (650 2350);
PAINT SKYBLUE (650 2350);
FORCEPROP 1 LAST PACK_TYPE 0402V
J 1
(650 2300);
DISPLAY 0.617021 (650 2300);
PAINT SKYBLUE (650 2300);
FORCEPROP 1 LAST MATERIAL X7R
J 0
(650 2350);
DISPLAY 0.617021 (650 2350);
PAINT SKYBLUE (650 2350);
FORCEPROP 1 LASTPIN (550 2500) $PN 1
J 0
(540 2515);
DISPLAY 0.617021 (540 2515);
PAINT ORANGE (540 2515);
FORCEPROP 1 LAST VOLTAGE 25V
J 0
(650 2400);
DISPLAY 0.617021 (650 2400);
PAINT SKYBLUE (650 2400);
FORCEPROP 1 LAST VALUE 0.01UF
J 2
(650 2400);
DISPLAY 0.617021 (650 2400);
PAINT SKYBLUE (650 2400);
FORCEPROP 1 LAST PART_NUMBER A36096-045
J 1
(650 2550);
DISPLAY 0.617021 (650 2550);
PAINT BLUE (650 2550);
FORCEPROP 1 LASTPIN (750 2500) $PN 2
J 0
(735 2515);
DISPLAY 0.617021 (735 2515);
PAINT ORANGE (735 2515);
FORCEPROP 2 LAST ROOM ST_SATA
J 0
(550 2650);
DISPLAY 1.361702 (550 2650);
PAINT ORANGE (550 2650);
DISPLAY INVISIBLE (550 2650);
FORCEPROP 2 LAST CDS_LOCATION C2L27
J 1
(650 2600);
DISPLAY 0.617021 (650 2600);
PAINT AQUA (650 2600);
DISPLAY INVISIBLE (650 2600);
FORCEPROP 2 LAST BOM_COST ST_SATA
J 0
(550 2650);
DISPLAY 1.361702 (550 2650);
PAINT ORANGE (550 2650);
DISPLAY INVISIBLE (550 2650);
FORCEPROP 2 LAST CDS_LIB dev_discrete
J 0
(650 2500);
PAINT ORANGE (650 2500);
DISPLAY INVISIBLE (650 2500);
FORCEPROP 2 LAST CDS_SEC 1
J 0
(650 2650);
PAINT ORANGE (650 2650);
DISPLAY INVISIBLE (650 2650);
FORCEPROP 2 LAST SEC_TYPE 0402V
J 0
(650 2750);
DISPLAY 1.021277 (650 2750);
PAINT ORANGE (650 2750);
DISPLAY INVISIBLE (650 2750);
FORCEPROP 2 LAST SEC 1
J 0
(650 2750);
DISPLAY 0.680851 (650 2750);
PAINT MONO (650 2750);
DISPLAY INVISIBLE (650 2750);
FORCEPROP 1 LAST PATH I240
J 0
(650 2700);
DISPLAY 0.978723 (650 2700);
PAINT WHITE (650 2700);
DISPLAY INVISIBLE (650 2700);
FORCEADD CAP_A..2
(625 3300);
FORCEPROP 1 LAST LOCATION C2L23
J 1
(625 3400);
DISPLAY 0.617021 (625 3400);
PAINT AQUA (625 3400);
FORCEPROP 1 LAST PART_NUMBER A36096-045
J 1
(625 3350);
DISPLAY 0.617021 (625 3350);
PAINT BLUE (625 3350);
FORCEPROP 1 LAST VALUE 0.01UF
J 2
(625 3200);
DISPLAY 0.617021 (625 3200);
PAINT SKYBLUE (625 3200);
FORCEPROP 1 LAST TOLERANCE 10%
J 2
(625 3150);
DISPLAY 0.617021 (625 3150);
PAINT SKYBLUE (625 3150);
FORCEPROP 1 LAST PACK_TYPE 0402V
J 1
(625 3100);
DISPLAY 0.617021 (625 3100);
PAINT SKYBLUE (625 3100);
FORCEPROP 1 LAST VOLTAGE 25V
J 0
(625 3200);
DISPLAY 0.617021 (625 3200);
PAINT SKYBLUE (625 3200);
FORCEPROP 1 LAST MATERIAL X7R
J 0
(625 3150);
DISPLAY 0.617021 (625 3150);
PAINT SKYBLUE (625 3150);
FORCEPROP 1 LASTPIN (525 3300) $PN 1
J 0
(515 3315);
DISPLAY 0.617021 (515 3315);
PAINT ORANGE (515 3315);
FORCEPROP 1 LASTPIN (725 3300) $PN 2
J 0
(710 3315);
DISPLAY 0.617021 (710 3315);
PAINT ORANGE (710 3315);
FORCEPROP 2 LAST ROOM ST_SATA
J 0
(525 3450);
DISPLAY 1.361702 (525 3450);
PAINT ORANGE (525 3450);
DISPLAY INVISIBLE (525 3450);
FORCEPROP 2 LAST CDS_LOCATION C2L23
J 1
(625 3400);
DISPLAY 0.617021 (625 3400);
PAINT AQUA (625 3400);
DISPLAY INVISIBLE (625 3400);
FORCEPROP 2 LAST BOM_COST ST_SATA
J 0
(525 3450);
DISPLAY 1.361702 (525 3450);
PAINT ORANGE (525 3450);
DISPLAY INVISIBLE (525 3450);
FORCEPROP 2 LAST CDS_LIB dev_discrete
J 0
(625 3300);
PAINT ORANGE (625 3300);
DISPLAY INVISIBLE (625 3300);
FORCEPROP 2 LAST CDS_SEC 1
J 0
(625 3450);
PAINT ORANGE (625 3450);
DISPLAY INVISIBLE (625 3450);
FORCEPROP 2 LAST SEC_TYPE 0402V
J 0
(625 3550);
DISPLAY 1.021277 (625 3550);
PAINT ORANGE (625 3550);
DISPLAY INVISIBLE (625 3550);
FORCEPROP 2 LAST SEC 1
J 0
(625 3550);
DISPLAY 0.680851 (625 3550);
PAINT MONO (625 3550);
DISPLAY INVISIBLE (625 3550);
FORCEPROP 1 LAST PATH I241
J 0
(625 3500);
DISPLAY 0.978723 (625 3500);
PAINT WHITE (625 3500);
DISPLAY INVISIBLE (625 3500);
FORCEADD CAP_A..2
(625 3650);
FORCEPROP 1 LAST LOCATION C2L41
J 1
(625 3750);
DISPLAY 0.617021 (625 3750);
PAINT AQUA (625 3750);
FORCEPROP 1 LAST VALUE 0.01UF
J 2
(625 3550);
DISPLAY 0.617021 (625 3550);
PAINT SKYBLUE (625 3550);
FORCEPROP 1 LAST TOLERANCE 10%
J 2
(625 3500);
DISPLAY 0.617021 (625 3500);
PAINT SKYBLUE (625 3500);
FORCEPROP 1 LAST PACK_TYPE 0402V
J 1
(625 3450);
DISPLAY 0.617021 (625 3450);
PAINT SKYBLUE (625 3450);
FORCEPROP 1 LAST MATERIAL X7R
J 0
(625 3500);
DISPLAY 0.617021 (625 3500);
PAINT SKYBLUE (625 3500);
FORCEPROP 1 LASTPIN (725 3650) $PN 2
J 0
(710 3665);
DISPLAY 0.617021 (710 3665);
PAINT ORANGE (710 3665);
FORCEPROP 1 LASTPIN (525 3650) $PN 1
J 0
(515 3665);
DISPLAY 0.617021 (515 3665);
PAINT ORANGE (515 3665);
FORCEPROP 1 LAST VOLTAGE 25V
J 0
(625 3550);
DISPLAY 0.617021 (625 3550);
PAINT SKYBLUE (625 3550);
FORCEPROP 1 LAST PART_NUMBER A36096-045
J 1
(625 3700);
DISPLAY 0.617021 (625 3700);
PAINT BLUE (625 3700);
FORCEPROP 2 LAST ROOM ST_SATA
J 0
(550 3800);
DISPLAY 1.361702 (550 3800);
PAINT ORANGE (550 3800);
DISPLAY INVISIBLE (550 3800);
FORCEPROP 1 LAST PATH I242
J 0
(625 3850);
DISPLAY 0.978723 (625 3850);
PAINT WHITE (625 3850);
DISPLAY INVISIBLE (625 3850);
FORCEPROP 2 LAST SEC 1
J 0
(625 3900);
DISPLAY 0.680851 (625 3900);
PAINT MONO (625 3900);
DISPLAY INVISIBLE (625 3900);
FORCEPROP 2 LAST SEC_TYPE 0402V
J 0
(625 3900);
DISPLAY 1.021277 (625 3900);
PAINT ORANGE (625 3900);
DISPLAY INVISIBLE (625 3900);
FORCEPROP 2 LAST CDS_SEC 1
J 0
(625 3800);
PAINT ORANGE (625 3800);
DISPLAY INVISIBLE (625 3800);
FORCEPROP 2 LAST CDS_LIB dev_discrete
J 0
(625 3650);
PAINT ORANGE (625 3650);
DISPLAY INVISIBLE (625 3650);
FORCEPROP 2 LAST BOM_COST ST_SATA
J 0
(550 3800);
DISPLAY 1.361702 (550 3800);
PAINT ORANGE (550 3800);
DISPLAY INVISIBLE (550 3800);
FORCEPROP 2 LAST CDS_LOCATION C2L41
J 1
(625 3750);
DISPLAY 0.617021 (625 3750);
PAINT AQUA (625 3750);
DISPLAY INVISIBLE (625 3750);
FORCEADD TAP..1
(1300 2350);
FORCEPROP 3 LASTPIN (1250 2350) SIG_NAME SATA6G_PCH_PCIE_UP_SATA_TXN<5>
J 0
(1260 2360);
DISPLAY 0.659574 (1260 2360);
PAINT MONO (1260 2360);
DISPLAY INVISIBLE (1260 2360);
FORCEPROP 1 LASTPIN (1250 2350) BN 5
J 0
(1238 2358);
DISPLAY 0.617021 (1238 2358);
PAINT GREEN (1238 2358);
FORCEPROP 2 LAST CDS_LIB mstr_standard
J 0
(1300 2350);
PAINT ORANGE (1300 2350);
DISPLAY INVISIBLE (1300 2350);
FORCEPROP 1 LAST BODY_TYPE PLUMBING
J 0
(1300 2400);
DISPLAY 0.872340 (1300 2400);
PAINT GREEN (1300 2400);
DISPLAY INVISIBLE (1300 2400);
FORCEPROP 1 LAST HDL_TAP TRUE
J 0
(1625 2225);
DISPLAY 0.872340 (1625 2225);
PAINT ORANGE (1625 2225);
DISPLAY INVISIBLE (1625 2225);
FORCEPROP 1 LAST PATH I251
J 0
(1298 2350);
DISPLAY 0.872340 (1298 2350);
PAINT GREEN (1298 2350);
DISPLAY INVISIBLE (1298 2350);
FORCEADD TAP..1
(1450 2050);
FORCEPROP 3 LASTPIN (1400 2050) SIG_NAME SATA6G_PCH_PCIE_UP_SATA_TXP<6>
J 0
(1410 2060);
DISPLAY 0.659574 (1410 2060);
PAINT MONO (1410 2060);
DISPLAY INVISIBLE (1410 2060);
FORCEPROP 1 LASTPIN (1400 2050) BN 6
J 0
(1388 2058);
DISPLAY 0.617021 (1388 2058);
PAINT GREEN (1388 2058);
FORCEPROP 2 LAST CDS_LIB mstr_standard
J 0
(1450 2050);
PAINT ORANGE (1450 2050);
DISPLAY INVISIBLE (1450 2050);
FORCEPROP 1 LAST BODY_TYPE PLUMBING
J 0
(1450 2100);
DISPLAY 0.872340 (1450 2100);
PAINT GREEN (1450 2100);
DISPLAY INVISIBLE (1450 2100);
FORCEPROP 1 LAST HDL_TAP TRUE
J 0
(1775 1925);
DISPLAY 0.872340 (1775 1925);
PAINT ORANGE (1775 1925);
DISPLAY INVISIBLE (1775 1925);
FORCEPROP 1 LAST PATH I252
J 0
(1448 2050);
DISPLAY 0.872340 (1448 2050);
PAINT GREEN (1448 2050);
DISPLAY INVISIBLE (1448 2050);
FORCEADD TAP..1
(1450 1700);
FORCEPROP 3 LASTPIN (1400 1700) SIG_NAME SATA6G_PCH_PCIE_UP_SATA_TXP<7>
J 0
(1410 1710);
DISPLAY 0.659574 (1410 1710);
PAINT MONO (1410 1710);
DISPLAY INVISIBLE (1410 1710);
FORCEPROP 1 LASTPIN (1400 1700) BN 7
J 0
(1388 1708);
DISPLAY 0.617021 (1388 1708);
PAINT GREEN (1388 1708);
FORCEPROP 1 LAST PATH I253
J 0
(1448 1700);
DISPLAY 0.872340 (1448 1700);
PAINT GREEN (1448 1700);
DISPLAY INVISIBLE (1448 1700);
FORCEPROP 1 LAST HDL_TAP TRUE
J 0
(1775 1575);
DISPLAY 0.872340 (1775 1575);
PAINT ORANGE (1775 1575);
DISPLAY INVISIBLE (1775 1575);
FORCEPROP 1 LAST BODY_TYPE PLUMBING
J 0
(1450 1750);
DISPLAY 0.872340 (1450 1750);
PAINT GREEN (1450 1750);
DISPLAY INVISIBLE (1450 1750);
FORCEPROP 2 LAST CDS_LIB mstr_standard
J 0
(1450 1700);
PAINT ORANGE (1450 1700);
DISPLAY INVISIBLE (1450 1700);
FORCEADD TAP..1
(1300 1900);
FORCEPROP 3 LASTPIN (1250 1900) SIG_NAME SATA6G_PCH_PCIE_UP_SATA_TXN<6>
J 0
(1260 1910);
DISPLAY 0.659574 (1260 1910);
PAINT MONO (1260 1910);
DISPLAY INVISIBLE (1260 1910);
FORCEPROP 1 LASTPIN (1250 1900) BN 6
J 0
(1238 1908);
DISPLAY 0.617021 (1238 1908);
PAINT GREEN (1238 1908);
FORCEPROP 2 LAST CDS_LIB mstr_standard
J 0
(1300 1900);
PAINT ORANGE (1300 1900);
DISPLAY INVISIBLE (1300 1900);
FORCEPROP 1 LAST BODY_TYPE PLUMBING
J 0
(1300 1950);
DISPLAY 0.872340 (1300 1950);
PAINT GREEN (1300 1950);
DISPLAY INVISIBLE (1300 1950);
FORCEPROP 1 LAST HDL_TAP TRUE
J 0
(1625 1775);
DISPLAY 0.872340 (1625 1775);
PAINT ORANGE (1625 1775);
DISPLAY INVISIBLE (1625 1775);
FORCEPROP 1 LAST PATH I254
J 0
(1298 1900);
DISPLAY 0.872340 (1298 1900);
PAINT GREEN (1298 1900);
DISPLAY INVISIBLE (1298 1900);
FORCEADD CAP_A..2
(1025 2350);
FORCEPROP 1 LAST LOCATION C2L26
J 1
(1025 2450);
DISPLAY 0.617021 (1025 2450);
PAINT AQUA (1025 2450);
FORCEPROP 1 LAST PART_NUMBER A36096-045
J 1
(1025 2400);
DISPLAY 0.617021 (1025 2400);
PAINT BLUE (1025 2400);
FORCEPROP 1 LAST VALUE 0.01UF
J 2
(1025 2250);
DISPLAY 0.617021 (1025 2250);
PAINT SKYBLUE (1025 2250);
FORCEPROP 1 LAST TOLERANCE 10%
J 2
(1025 2200);
DISPLAY 0.617021 (1025 2200);
PAINT SKYBLUE (1025 2200);
FORCEPROP 1 LAST PACK_TYPE 0402V
J 1
(1025 2150);
DISPLAY 0.617021 (1025 2150);
PAINT SKYBLUE (1025 2150);
FORCEPROP 1 LAST VOLTAGE 25V
J 0
(1025 2250);
DISPLAY 0.617021 (1025 2250);
PAINT SKYBLUE (1025 2250);
FORCEPROP 1 LAST MATERIAL X7R
J 0
(1025 2200);
DISPLAY 0.617021 (1025 2200);
PAINT SKYBLUE (1025 2200);
FORCEPROP 1 LASTPIN (925 2350) $PN 1
J 0
(915 2365);
DISPLAY 0.617021 (915 2365);
PAINT ORANGE (915 2365);
FORCEPROP 1 LASTPIN (1125 2350) $PN 2
J 0
(1110 2365);
DISPLAY 0.617021 (1110 2365);
PAINT ORANGE (1110 2365);
FORCEPROP 2 LAST ROOM ST_SATA
J 0
(975 2500);
DISPLAY 1.361702 (975 2500);
PAINT ORANGE (975 2500);
DISPLAY INVISIBLE (975 2500);
FORCEPROP 2 LAST CDS_LOCATION C2L26
J 1
(1025 2450);
DISPLAY 0.617021 (1025 2450);
PAINT AQUA (1025 2450);
DISPLAY INVISIBLE (1025 2450);
FORCEPROP 2 LAST BOM_COST ST_SATA
J 0
(975 2500);
DISPLAY 1.361702 (975 2500);
PAINT ORANGE (975 2500);
DISPLAY INVISIBLE (975 2500);
FORCEPROP 2 LAST CDS_LIB dev_discrete
J 0
(1025 2350);
PAINT ORANGE (1025 2350);
DISPLAY INVISIBLE (1025 2350);
FORCEPROP 2 LAST CDS_SEC 1
J 0
(1025 2500);
PAINT ORANGE (1025 2500);
DISPLAY INVISIBLE (1025 2500);
FORCEPROP 2 LAST SEC_TYPE 0402V
J 0
(1025 2600);
DISPLAY 1.021277 (1025 2600);
PAINT ORANGE (1025 2600);
DISPLAY INVISIBLE (1025 2600);
FORCEPROP 2 LAST SEC 1
J 0
(1025 2600);
DISPLAY 0.680851 (1025 2600);
PAINT MONO (1025 2600);
DISPLAY INVISIBLE (1025 2600);
FORCEPROP 1 LAST PATH I255
J 0
(1025 2550);
DISPLAY 0.978723 (1025 2550);
PAINT WHITE (1025 2550);
DISPLAY INVISIBLE (1025 2550);
FORCEADD CAP_A..2
(1050 1900);
FORCEPROP 1 LAST LOCATION C2L38
J 1
(1050 2000);
DISPLAY 0.617021 (1050 2000);
PAINT AQUA (1050 2000);
FORCEPROP 1 LAST TOLERANCE 10%
J 2
(1050 1750);
DISPLAY 0.617021 (1050 1750);
PAINT SKYBLUE (1050 1750);
FORCEPROP 1 LAST PACK_TYPE 0402V
J 1
(1050 1700);
DISPLAY 0.617021 (1050 1700);
PAINT SKYBLUE (1050 1700);
FORCEPROP 1 LAST VOLTAGE 25V
J 0
(1050 1800);
DISPLAY 0.617021 (1050 1800);
PAINT SKYBLUE (1050 1800);
FORCEPROP 1 LAST MATERIAL X7R
J 0
(1050 1750);
DISPLAY 0.617021 (1050 1750);
PAINT SKYBLUE (1050 1750);
FORCEPROP 1 LASTPIN (1150 1900) $PN 2
J 0
(1135 1915);
DISPLAY 0.617021 (1135 1915);
PAINT ORANGE (1135 1915);
FORCEPROP 1 LASTPIN (950 1900) $PN 1
J 0
(940 1915);
DISPLAY 0.617021 (940 1915);
PAINT ORANGE (940 1915);
FORCEPROP 1 LAST PART_NUMBER A36096-045
J 1
(1050 1950);
DISPLAY 0.617021 (1050 1950);
PAINT BLUE (1050 1950);
FORCEPROP 1 LAST VALUE 0.01UF
J 2
(1050 1800);
DISPLAY 0.617021 (1050 1800);
PAINT SKYBLUE (1050 1800);
FORCEPROP 2 LAST ROOM ST_SATA
J 0
(975 2050);
DISPLAY 1.361702 (975 2050);
PAINT ORANGE (975 2050);
DISPLAY INVISIBLE (975 2050);
FORCEPROP 2 LAST CDS_LOCATION C2L38
J 1
(1050 2000);
DISPLAY 0.617021 (1050 2000);
PAINT AQUA (1050 2000);
DISPLAY INVISIBLE (1050 2000);
FORCEPROP 2 LAST BOM_COST ST_SATA
J 0
(975 2050);
DISPLAY 1.361702 (975 2050);
PAINT ORANGE (975 2050);
DISPLAY INVISIBLE (975 2050);
FORCEPROP 2 LAST CDS_LIB dev_discrete
J 0
(1050 1900);
PAINT ORANGE (1050 1900);
DISPLAY INVISIBLE (1050 1900);
FORCEPROP 2 LAST CDS_SEC 1
J 0
(1050 2050);
PAINT ORANGE (1050 2050);
DISPLAY INVISIBLE (1050 2050);
FORCEPROP 2 LAST SEC_TYPE 0402V
J 0
(1050 2150);
DISPLAY 1.021277 (1050 2150);
PAINT ORANGE (1050 2150);
DISPLAY INVISIBLE (1050 2150);
FORCEPROP 2 LAST SEC 1
J 0
(1050 2150);
DISPLAY 0.680851 (1050 2150);
PAINT MONO (1050 2150);
DISPLAY INVISIBLE (1050 2150);
FORCEPROP 1 LAST PATH I256
J 0
(1050 2100);
DISPLAY 0.978723 (1050 2100);
PAINT WHITE (1050 2100);
DISPLAY INVISIBLE (1050 2100);
FORCEADD CAP_A..2
(650 2050);
FORCEPROP 1 LAST PART_NUMBER A36096-045
J 1
(650 2100);
DISPLAY 0.617021 (650 2100);
PAINT BLUE (650 2100);
FORCEPROP 1 LAST VALUE 0.01UF
J 2
(650 1950);
DISPLAY 0.617021 (650 1950);
PAINT SKYBLUE (650 1950);
FORCEPROP 1 LAST TOLERANCE 10%
J 2
(650 1900);
DISPLAY 0.617021 (650 1900);
PAINT SKYBLUE (650 1900);
FORCEPROP 1 LAST PACK_TYPE 0402V
J 1
(650 1850);
DISPLAY 0.617021 (650 1850);
PAINT SKYBLUE (650 1850);
FORCEPROP 1 LAST VOLTAGE 25V
J 0
(650 1950);
DISPLAY 0.617021 (650 1950);
PAINT SKYBLUE (650 1950);
FORCEPROP 1 LAST MATERIAL X7R
J 0
(650 1900);
DISPLAY 0.617021 (650 1900);
PAINT SKYBLUE (650 1900);
FORCEPROP 1 LASTPIN (750 2050) $PN 2
J 0
(735 2065);
DISPLAY 0.617021 (735 2065);
PAINT ORANGE (735 2065);
FORCEPROP 1 LASTPIN (550 2050) $PN 1
J 0
(540 2065);
DISPLAY 0.617021 (540 2065);
PAINT ORANGE (540 2065);
FORCEPROP 1 LAST LOCATION C2L48
J 1
(650 2150);
DISPLAY 0.617021 (650 2150);
PAINT AQUA (650 2150);
FORCEPROP 2 LAST ROOM ST_SATA
J 0
(550 2200);
DISPLAY 1.361702 (550 2200);
PAINT ORANGE (550 2200);
DISPLAY INVISIBLE (550 2200);
FORCEPROP 2 LAST CDS_LOCATION C2L48
J 1
(650 2150);
DISPLAY 0.617021 (650 2150);
PAINT AQUA (650 2150);
DISPLAY INVISIBLE (650 2150);
FORCEPROP 2 LAST BOM_COST ST_SATA
J 0
(550 2200);
DISPLAY 1.361702 (550 2200);
PAINT ORANGE (550 2200);
DISPLAY INVISIBLE (550 2200);
FORCEPROP 2 LAST CDS_LIB dev_discrete
J 0
(650 2050);
PAINT ORANGE (650 2050);
DISPLAY INVISIBLE (650 2050);
FORCEPROP 2 LAST CDS_SEC 1
J 0
(650 2200);
PAINT ORANGE (650 2200);
DISPLAY INVISIBLE (650 2200);
FORCEPROP 2 LAST SEC_TYPE 0402V
J 0
(650 2300);
DISPLAY 1.021277 (650 2300);
PAINT ORANGE (650 2300);
DISPLAY INVISIBLE (650 2300);
FORCEPROP 2 LAST SEC 1
J 0
(650 2300);
DISPLAY 0.680851 (650 2300);
PAINT MONO (650 2300);
DISPLAY INVISIBLE (650 2300);
FORCEPROP 1 LAST PATH I257
J 0
(650 2250);
DISPLAY 0.978723 (650 2250);
PAINT WHITE (650 2250);
DISPLAY INVISIBLE (650 2250);
FORCEADD CAP_A..2
(650 1700);
FORCEPROP 1 LAST VALUE 0.01UF
J 2
(650 1600);
DISPLAY 0.617021 (650 1600);
PAINT SKYBLUE (650 1600);
FORCEPROP 1 LAST TOLERANCE 10%
J 2
(650 1550);
DISPLAY 0.617021 (650 1550);
PAINT SKYBLUE (650 1550);
FORCEPROP 1 LAST VOLTAGE 25V
J 0
(650 1600);
DISPLAY 0.617021 (650 1600);
PAINT SKYBLUE (650 1600);
FORCEPROP 1 LAST MATERIAL X7R
J 0
(650 1550);
DISPLAY 0.617021 (650 1550);
PAINT SKYBLUE (650 1550);
FORCEPROP 1 LAST LOCATION C2L24
J 1
(650 1800);
DISPLAY 0.617021 (650 1800);
PAINT AQUA (650 1800);
FORCEPROP 1 LAST PACK_TYPE 0402V
J 1
(650 1500);
DISPLAY 0.617021 (650 1500);
PAINT SKYBLUE (650 1500);
FORCEPROP 1 LASTPIN (750 1700) $PN 2
J 0
(735 1715);
DISPLAY 0.617021 (735 1715);
PAINT ORANGE (735 1715);
FORCEPROP 1 LASTPIN (550 1700) $PN 1
J 0
(540 1715);
DISPLAY 0.617021 (540 1715);
PAINT ORANGE (540 1715);
FORCEPROP 1 LAST PART_NUMBER A36096-045
J 1
(650 1750);
DISPLAY 0.617021 (650 1750);
PAINT BLUE (650 1750);
FORCEPROP 2 LAST ROOM ST_SATA
J 0
(550 1850);
DISPLAY 1.361702 (550 1850);
PAINT ORANGE (550 1850);
DISPLAY INVISIBLE (550 1850);
FORCEPROP 1 LAST PATH I258
J 0
(650 1900);
DISPLAY 0.978723 (650 1900);
PAINT WHITE (650 1900);
DISPLAY INVISIBLE (650 1900);
FORCEPROP 2 LAST SEC 1
J 0
(650 1950);
DISPLAY 0.680851 (650 1950);
PAINT MONO (650 1950);
DISPLAY INVISIBLE (650 1950);
FORCEPROP 2 LAST SEC_TYPE 0402V
J 0
(650 1950);
DISPLAY 1.021277 (650 1950);
PAINT ORANGE (650 1950);
DISPLAY INVISIBLE (650 1950);
FORCEPROP 2 LAST CDS_SEC 1
J 0
(650 1850);
PAINT ORANGE (650 1850);
DISPLAY INVISIBLE (650 1850);
FORCEPROP 2 LAST CDS_LIB dev_discrete
J 0
(650 1700);
PAINT ORANGE (650 1700);
DISPLAY INVISIBLE (650 1700);
FORCEPROP 2 LAST BOM_COST ST_SATA
J 0
(550 1850);
DISPLAY 1.361702 (550 1850);
PAINT ORANGE (550 1850);
DISPLAY INVISIBLE (550 1850);
FORCEPROP 2 LAST CDS_LOCATION C2L24
J 1
(650 1800);
DISPLAY 0.617021 (650 1800);
PAINT AQUA (650 1800);
DISPLAY INVISIBLE (650 1800);
FORCEADD CAP_A..2
(1050 1550);
FORCEPROP 1 LAST LOCATION C2L21
J 1
(1050 1650);
DISPLAY 0.617021 (1050 1650);
PAINT AQUA (1050 1650);
FORCEPROP 1 LAST PART_NUMBER A36096-045
J 1
(1050 1600);
DISPLAY 0.617021 (1050 1600);
PAINT BLUE (1050 1600);
FORCEPROP 1 LAST TOLERANCE 10%
J 2
(1050 1400);
DISPLAY 0.617021 (1050 1400);
PAINT SKYBLUE (1050 1400);
FORCEPROP 1 LAST PACK_TYPE 0402V
J 1
(1050 1350);
DISPLAY 0.617021 (1050 1350);
PAINT SKYBLUE (1050 1350);
FORCEPROP 1 LAST VOLTAGE 25V
J 0
(1050 1450);
DISPLAY 0.617021 (1050 1450);
PAINT SKYBLUE (1050 1450);
FORCEPROP 1 LAST MATERIAL X7R
J 0
(1050 1400);
DISPLAY 0.617021 (1050 1400);
PAINT SKYBLUE (1050 1400);
FORCEPROP 1 LASTPIN (1150 1550) $PN 2
J 0
(1135 1565);
DISPLAY 0.617021 (1135 1565);
PAINT ORANGE (1135 1565);
FORCEPROP 1 LASTPIN (950 1550) $PN 1
J 0
(940 1565);
DISPLAY 0.617021 (940 1565);
PAINT ORANGE (940 1565);
FORCEPROP 1 LAST VALUE 0.01UF
J 2
(1050 1450);
DISPLAY 0.617021 (1050 1450);
PAINT SKYBLUE (1050 1450);
FORCEPROP 2 LAST ROOM ST_SATA
J 0
(975 1700);
DISPLAY 1.361702 (975 1700);
PAINT ORANGE (975 1700);
DISPLAY INVISIBLE (975 1700);
FORCEPROP 2 LAST CDS_LOCATION C2L21
J 1
(1050 1650);
DISPLAY 0.617021 (1050 1650);
PAINT AQUA (1050 1650);
DISPLAY INVISIBLE (1050 1650);
FORCEPROP 2 LAST BOM_COST ST_SATA
J 0
(975 1700);
DISPLAY 1.361702 (975 1700);
PAINT ORANGE (975 1700);
DISPLAY INVISIBLE (975 1700);
FORCEPROP 2 LAST CDS_LIB dev_discrete
J 0
(1050 1550);
PAINT ORANGE (1050 1550);
DISPLAY INVISIBLE (1050 1550);
FORCEPROP 2 LAST CDS_SEC 1
J 0
(1050 1700);
PAINT ORANGE (1050 1700);
DISPLAY INVISIBLE (1050 1700);
FORCEPROP 2 LAST SEC_TYPE 0402V
J 0
(1050 1800);
DISPLAY 1.021277 (1050 1800);
PAINT ORANGE (1050 1800);
DISPLAY INVISIBLE (1050 1800);
FORCEPROP 2 LAST SEC 1
J 0
(1050 1800);
DISPLAY 0.680851 (1050 1800);
PAINT MONO (1050 1800);
DISPLAY INVISIBLE (1050 1800);
FORCEPROP 1 LAST PATH I259
J 0
(1050 1750);
DISPLAY 0.978723 (1050 1750);
PAINT WHITE (1050 1750);
DISPLAY INVISIBLE (1050 1750);
FORCEADD P3V3..1
(-4075 2300);
FORCEPROP 3 LASTPIN (-4075 2250) SIG_NAME P3V3\g
J 0
(-4065 2260);
DISPLAY 0.659574 (-4065 2260);
PAINT MONO (-4065 2260);
DISPLAY INVISIBLE (-4065 2260);
FORCEPROP 1 LAST VOLTAGE 3.3V
J 0
(-4120 2257);
DISPLAY 0.340426 (-4120 2257);
PAINT SKYBLUE (-4120 2257);
DISPLAY INVISIBLE (-4120 2257);
FORCEPROP 1 LAST HDL_POWER P3V3
J 0
(-4400 2175);
DISPLAY 1.170213 (-4400 2175);
PAINT GREEN (-4400 2175);
DISPLAY INVISIBLE (-4400 2175);
FORCEPROP 2 LAST ROOM ST_SATA
J 0
(-3975 2400);
DISPLAY 1.361702 (-3975 2400);
PAINT ORANGE (-3975 2400);
DISPLAY INVISIBLE (-3975 2400);
FORCEPROP 1 LAST PATH I260
J 0
(-4030 2302);
DISPLAY 0.340426 (-4030 2302);
PAINT GREEN (-4030 2302);
DISPLAY INVISIBLE (-4030 2302);
FORCEPROP 1 LAST BODY_TYPE PLUMBING
J 0
(-4120 2257);
DISPLAY 0.446809 (-4120 2257);
PAINT GREEN (-4120 2257);
DISPLAY INVISIBLE (-4120 2257);
FORCEPROP 2 LAST CDS_LIB mstr_symbols
J 0
(-4075 2300);
PAINT MONO (-4075 2300);
DISPLAY INVISIBLE (-4075 2300);
FORCEPROP 2 LAST BOM_COST ST_SATA
J 0
(-3975 2400);
DISPLAY 1.361702 (-3975 2400);
PAINT ORANGE (-3975 2400);
DISPLAY INVISIBLE (-3975 2400);
FORCEPROP 1 LAST SIZE 1B
J 0
(-4030 2322);
DISPLAY 0.446809 (-4030 2322);
PAINT GREEN (-4030 2322);
DISPLAY INVISIBLE (-4030 2322);
FORCEADD RES..1
(-3900 2200);
FORCEPROP 1 LAST LOCATION R2L23
J 0
(-3950 2250);
DISPLAY 0.617021 (-3950 2250);
PAINT AQUA (-3950 2250);
FORCEPROP 1 LAST PART_NUMBER G21796-001
J 0
(-3950 2300);
DISPLAY 0.617021 (-3950 2300);
PAINT BLUE (-3950 2300);
FORCEPROP 1 LAST VALUE 2.0K
J 2
(-3925 2100);
DISPLAY 0.617021 (-3925 2100);
PAINT SKYBLUE (-3925 2100);
FORCEPROP 1 LAST TOLERANCE 1%
J 0
(-3900 2100);
DISPLAY 0.617021 (-3900 2100);
PAINT SKYBLUE (-3900 2100);
FORCEPROP 1 LAST PACK_TYPE 0402
J 0
(-3650 2050);
DISPLAY 0.617021 (-3650 2050);
PAINT SKYBLUE (-3650 2050);
FORCEPROP 1 LAST MATERIAL CHIP
J 0
(-3900 2050);
DISPLAY 0.617021 (-3900 2050);
PAINT SKYBLUE (-3900 2050);
FORCEPROP 1 LASTPIN (-3800 2200) $PN 2
J 0
(-3838 2212);
DISPLAY 0.617021 (-3838 2212);
PAINT ORANGE (-3838 2212);
FORCEPROP 1 LASTPIN (-4000 2200) $PN 1
J 0
(-3988 2212);
DISPLAY 0.617021 (-3988 2212);
PAINT ORANGE (-3988 2212);
FORCEPROP 1 LAST WATTAGE 1/16W
J 2
(-3925 2050);
DISPLAY 0.617021 (-3925 2050);
PAINT SKYBLUE (-3925 2050);
FORCEPROP 2 LAST ROOM ST_SATA
J 0
(-3850 2375);
DISPLAY 1.361702 (-3850 2375);
PAINT ORANGE (-3850 2375);
DISPLAY INVISIBLE (-3850 2375);
FORCEPROP 2 LAST SEC_TYPE 0402
J 0
(-3950 2400);
DISPLAY 1.021277 (-3950 2400);
PAINT ORANGE (-3950 2400);
DISPLAY INVISIBLE (-3950 2400);
FORCEPROP 2 LAST CDS_LIB mstr_discrete
J 0
(-3900 2200);
PAINT ORANGE (-3900 2200);
DISPLAY INVISIBLE (-3900 2200);
FORCEPROP 2 LAST BOM_COST ST_SATA
J 0
(-3850 2375);
DISPLAY 1.361702 (-3850 2375);
PAINT ORANGE (-3850 2375);
DISPLAY INVISIBLE (-3850 2375);
FORCEPROP 2 LAST SEC 1
J 0
(-3950 2400);
DISPLAY 0.680851 (-3950 2400);
PAINT MONO (-3950 2400);
DISPLAY INVISIBLE (-3950 2400);
FORCEPROP 2 LAST CDS_LOCATION R2L23
J 0
(-3950 2250);
DISPLAY 0.617021 (-3950 2250);
PAINT AQUA (-3950 2250);
DISPLAY INVISIBLE (-3950 2250);
FORCEPROP 1 LAST PATH I261
J 0
(-3950 2350);
DISPLAY 0.978723 (-3950 2350);
PAINT WHITE (-3950 2350);
DISPLAY INVISIBLE (-3950 2350);
FORCEADD P3V3..1
(-3900 5025);
FORCEPROP 3 LASTPIN (-3900 4975) SIG_NAME P3V3\g
J 0
(-3890 4985);
DISPLAY 0.659574 (-3890 4985);
PAINT MONO (-3890 4985);
DISPLAY INVISIBLE (-3890 4985);
FORCEPROP 1 LAST VOLTAGE 3.3V
J 0
(-3945 4982);
DISPLAY 0.340426 (-3945 4982);
PAINT SKYBLUE (-3945 4982);
DISPLAY INVISIBLE (-3945 4982);
FORCEPROP 1 LAST HDL_POWER P3V3
J 0
(-4225 4900);
DISPLAY 1.170213 (-4225 4900);
PAINT GREEN (-4225 4900);
DISPLAY INVISIBLE (-4225 4900);
FORCEPROP 2 LAST ROOM ST_SATA
J 0
(-3800 5125);
DISPLAY 1.361702 (-3800 5125);
PAINT ORANGE (-3800 5125);
DISPLAY INVISIBLE (-3800 5125);
FORCEPROP 2 LAST CDS_LIB mstr_symbols
J 0
(-3900 5025);
PAINT ORANGE (-3900 5025);
DISPLAY INVISIBLE (-3900 5025);
FORCEPROP 2 LAST BOM_COST ST_SATA
J 0
(-3800 5125);
DISPLAY 1.361702 (-3800 5125);
PAINT ORANGE (-3800 5125);
DISPLAY INVISIBLE (-3800 5125);
FORCEPROP 1 LAST SIZE 1B
J 0
(-3855 5047);
DISPLAY 0.446809 (-3855 5047);
PAINT GREEN (-3855 5047);
DISPLAY INVISIBLE (-3855 5047);
FORCEPROP 1 LAST BODY_TYPE PLUMBING
J 0
(-3945 4982);
DISPLAY 0.446809 (-3945 4982);
PAINT GREEN (-3945 4982);
DISPLAY INVISIBLE (-3945 4982);
FORCEPROP 1 LAST PATH I262
J 0
(-3855 5027);
DISPLAY 0.340426 (-3855 5027);
PAINT GREEN (-3855 5027);
DISPLAY INVISIBLE (-3855 5027);
FORCEADD RES..2
(-3900 4675);
FORCEPROP 1 LAST LOCATION R2L21
J 0
(-3855 4800);
DISPLAY 0.617021 (-3855 4800);
PAINT AQUA (-3855 4800);
FORCEPROP 1 LAST PART_NUMBER G21796-001
J 0
(-3860 4550);
DISPLAY 0.617021 (-3860 4550);
PAINT BLUE (-3860 4550);
FORCEPROP 1 LAST VALUE 2.0K
J 0
(-3855 4750);
DISPLAY 0.617021 (-3855 4750);
PAINT SKYBLUE (-3855 4750);
FORCEPROP 1 LAST TOLERANCE 1%
J 0
(-3855 4700);
DISPLAY 0.617021 (-3855 4700);
PAINT SKYBLUE (-3855 4700);
FORCEPROP 1 LAST PACK_TYPE 0402
J 0
(-3860 4500);
DISPLAY 0.617021 (-3860 4500);
PAINT SKYBLUE (-3860 4500);
FORCEPROP 1 LAST MATERIAL CHIP
J 0
(-3860 4600);
DISPLAY 0.617021 (-3860 4600);
PAINT SKYBLUE (-3860 4600);
FORCEPROP 1 LAST WATTAGE 1/16W
J 0
(-3860 4650);
DISPLAY 0.617021 (-3860 4650);
PAINT SKYBLUE (-3860 4650);
FORCEPROP 1 LASTPIN (-3900 4575) $PN 2
J 0
(-3895 4585);
DISPLAY 0.617021 (-3895 4585);
PAINT ORANGE (-3895 4585);
FORCEPROP 1 LASTPIN (-3900 4775) $PN 1
J 0
(-3895 4737);
DISPLAY 0.617021 (-3895 4737);
PAINT ORANGE (-3895 4737);
FORCEPROP 2 LAST ROOM ST_SATA
J 0
(-3850 4850);
DISPLAY 1.361702 (-3850 4850);
PAINT ORANGE (-3850 4850);
DISPLAY INVISIBLE (-3850 4850);
FORCEPROP 2 LAST SEC_TYPE 0402
J 0
(-3850 4900);
DISPLAY 1.021277 (-3850 4900);
PAINT ORANGE (-3850 4900);
DISPLAY INVISIBLE (-3850 4900);
FORCEPROP 2 LAST CDS_LIB mstr_discrete
J 0
(-3900 4675);
PAINT ORANGE (-3900 4675);
DISPLAY INVISIBLE (-3900 4675);
FORCEPROP 2 LAST BOM_COST ST_SATA
J 0
(-3850 4850);
DISPLAY 1.361702 (-3850 4850);
PAINT ORANGE (-3850 4850);
DISPLAY INVISIBLE (-3850 4850);
FORCEPROP 2 LAST SEC 1
J 0
(-3850 4900);
DISPLAY 0.680851 (-3850 4900);
PAINT MONO (-3850 4900);
DISPLAY INVISIBLE (-3850 4900);
FORCEPROP 2 LAST CDS_LOCATION R2L21
J 0
(-3855 4800);
DISPLAY 0.617021 (-3855 4800);
PAINT AQUA (-3855 4800);
DISPLAY INVISIBLE (-3855 4800);
FORCEPROP 1 LAST PATH I263
J 0
(-3850 4850);
DISPLAY 0.978723 (-3850 4850);
PAINT WHITE (-3850 4850);
DISPLAY INVISIBLE (-3850 4850);
FORCEADD RES..2
(1625 2000);
FORCEPROP 1 LAST LOCATION R2L22
J 0
(1670 2125);
DISPLAY 0.617021 (1670 2125);
PAINT AQUA (1670 2125);
FORCEPROP 1 LAST PART_NUMBER G21796-026
J 0
(1665 1875);
DISPLAY 0.617021 (1665 1875);
PAINT BLUE (1665 1875);
FORCEPROP 1 LAST VALUE 1.00K
J 0
(1670 2075);
DISPLAY 0.617021 (1670 2075);
PAINT SKYBLUE (1670 2075);
FORCEPROP 1 LAST TOLERANCE 1%
J 0
(1670 2025);
DISPLAY 0.617021 (1670 2025);
PAINT SKYBLUE (1670 2025);
FORCEPROP 1 LAST PACK_TYPE 0402
J 0
(1665 1825);
DISPLAY 0.617021 (1665 1825);
PAINT SKYBLUE (1665 1825);
FORCEPROP 1 LAST MATERIAL CHIP
J 0
(1665 1925);
DISPLAY 0.617021 (1665 1925);
PAINT SKYBLUE (1665 1925);
FORCEPROP 1 LAST WATTAGE 1/16W
J 0
(1665 1975);
DISPLAY 0.617021 (1665 1975);
PAINT SKYBLUE (1665 1975);
FORCEPROP 1 LASTPIN (1625 1900) $PN 2
J 0
(1630 1910);
DISPLAY 0.617021 (1630 1910);
PAINT ORANGE (1630 1910);
FORCEPROP 1 LASTPIN (1625 2100) $PN 1
J 0
(1630 2062);
DISPLAY 0.617021 (1630 2062);
PAINT ORANGE (1630 2062);
FORCEPROP 2 LAST ROOM ST_SATA
J 0
(1675 2175);
DISPLAY 1.361702 (1675 2175);
PAINT ORANGE (1675 2175);
DISPLAY INVISIBLE (1675 2175);
FORCEPROP 2 LAST SEC_TYPE 0402
J 0
(1675 2225);
DISPLAY 1.021277 (1675 2225);
PAINT ORANGE (1675 2225);
DISPLAY INVISIBLE (1675 2225);
FORCEPROP 2 LAST BOM_COST ST_SATA
J 0
(1675 2175);
DISPLAY 1.361702 (1675 2175);
PAINT ORANGE (1675 2175);
DISPLAY INVISIBLE (1675 2175);
FORCEPROP 2 LAST CDS_LIB mstr_discrete
J 0
(1625 2000);
PAINT ORANGE (1625 2000);
DISPLAY INVISIBLE (1625 2000);
FORCEPROP 2 LAST SEC 1
J 0
(1675 2225);
DISPLAY 0.680851 (1675 2225);
PAINT MONO (1675 2225);
DISPLAY INVISIBLE (1675 2225);
FORCEPROP 2 LAST CDS_LOCATION R2L22
J 0
(1670 2125);
DISPLAY 0.617021 (1670 2125);
PAINT AQUA (1670 2125);
DISPLAY INVISIBLE (1670 2125);
FORCEPROP 1 LAST PATH I264
J 0
(1675 2175);
DISPLAY 0.978723 (1675 2175);
PAINT WHITE (1675 2175);
DISPLAY INVISIBLE (1675 2175);
FORCEADD GND..1
(1625 1700);
FORCEPROP 3 LASTPIN (1625 1750) SIG_NAME GND\g
J 0
(1635 1760);
DISPLAY 0.659574 (1635 1760);
PAINT MONO (1635 1760);
DISPLAY INVISIBLE (1635 1760);
FORCEPROP 1 LAST VOLTAGE 0.0V
J 0
(1580 1657);
DISPLAY 0.340426 (1580 1657);
PAINT SKYBLUE (1580 1657);
DISPLAY INVISIBLE (1580 1657);
FORCEPROP 1 LAST HDL_POWER GND
J 0
(1625 1850);
DISPLAY 1.170213 (1625 1850);
PAINT GREEN (1625 1850);
DISPLAY INVISIBLE (1625 1850);
FORCEPROP 2 LAST ROOM ST_SATA
J 0
(1650 1775);
DISPLAY 1.361702 (1650 1775);
PAINT ORANGE (1650 1775);
DISPLAY INVISIBLE (1650 1775);
FORCEPROP 2 LAST BOM_COST ST_SATA
J 0
(1650 1775);
DISPLAY 1.361702 (1650 1775);
PAINT ORANGE (1650 1775);
DISPLAY INVISIBLE (1650 1775);
FORCEPROP 1 LAST SIZE 1B
J 0
(1700 1650);
DISPLAY 1.170213 (1700 1650);
PAINT AQUA (1700 1650);
DISPLAY INVISIBLE (1700 1650);
FORCEPROP 2 LAST CDS_LIB mstr_symbols
J 0
(1625 1700);
PAINT ORANGE (1625 1700);
DISPLAY INVISIBLE (1625 1700);
FORCEPROP 1 LAST BODY_TYPE PLUMBING
J 0
(1580 1657);
DISPLAY 0.340426 (1580 1657);
PAINT GREEN (1580 1657);
DISPLAY INVISIBLE (1580 1657);
FORCEPROP 1 LAST PATH I265
J 0
(1700 1700);
DISPLAY 0.872340 (1700 1700);
PAINT AQUA (1700 1700);
DISPLAY INVISIBLE (1700 1700);
FORCEADD RES..2
(1675 3500);
FORCEPROP 1 LAST LOCATION R2L18
J 0
(1720 3625);
DISPLAY 0.617021 (1720 3625);
PAINT AQUA (1720 3625);
FORCEPROP 1 LAST PART_NUMBER G21796-026
J 0
(1715 3375);
DISPLAY 0.617021 (1715 3375);
PAINT BLUE (1715 3375);
FORCEPROP 1 LAST VALUE 1.00K
J 0
(1720 3575);
DISPLAY 0.617021 (1720 3575);
PAINT SKYBLUE (1720 3575);
FORCEPROP 1 LAST TOLERANCE 1%
J 0
(1720 3525);
DISPLAY 0.617021 (1720 3525);
PAINT SKYBLUE (1720 3525);
FORCEPROP 1 LAST PACK_TYPE 0402
J 0
(1715 3325);
DISPLAY 0.617021 (1715 3325);
PAINT SKYBLUE (1715 3325);
FORCEPROP 1 LAST MATERIAL CHIP
J 0
(1715 3425);
DISPLAY 0.617021 (1715 3425);
PAINT SKYBLUE (1715 3425);
FORCEPROP 1 LAST WATTAGE 1/16W
J 0
(1715 3475);
DISPLAY 0.617021 (1715 3475);
PAINT SKYBLUE (1715 3475);
FORCEPROP 1 LASTPIN (1675 3400) $PN 2
J 0
(1680 3410);
DISPLAY 0.617021 (1680 3410);
PAINT ORANGE (1680 3410);
FORCEPROP 1 LASTPIN (1675 3600) $PN 1
J 0
(1680 3562);
DISPLAY 0.617021 (1680 3562);
PAINT ORANGE (1680 3562);
FORCEPROP 2 LAST ROOM ST_SATA
J 0
(1725 3675);
DISPLAY 1.361702 (1725 3675);
PAINT ORANGE (1725 3675);
DISPLAY INVISIBLE (1725 3675);
FORCEPROP 2 LAST SEC_TYPE 0402
J 0
(1725 3725);
DISPLAY 1.021277 (1725 3725);
PAINT ORANGE (1725 3725);
DISPLAY INVISIBLE (1725 3725);
FORCEPROP 2 LAST CDS_LIB mstr_discrete
J 0
(1675 3500);
PAINT ORANGE (1675 3500);
DISPLAY INVISIBLE (1675 3500);
FORCEPROP 2 LAST BOM_COST ST_SATA
J 0
(1725 3675);
DISPLAY 1.361702 (1725 3675);
PAINT ORANGE (1725 3675);
DISPLAY INVISIBLE (1725 3675);
FORCEPROP 2 LAST SEC 1
J 0
(1725 3725);
DISPLAY 0.680851 (1725 3725);
PAINT MONO (1725 3725);
DISPLAY INVISIBLE (1725 3725);
FORCEPROP 2 LAST CDS_LOCATION R2L18
J 0
(1720 3625);
DISPLAY 0.617021 (1720 3625);
PAINT AQUA (1720 3625);
DISPLAY INVISIBLE (1720 3625);
FORCEPROP 1 LAST PATH I266
J 0
(1725 3675);
DISPLAY 0.978723 (1725 3675);
PAINT WHITE (1725 3675);
DISPLAY INVISIBLE (1725 3675);
FORCEADD GND..1
(1675 3275);
FORCEPROP 3 LASTPIN (1675 3325) SIG_NAME GND\g
J 0
(1685 3335);
DISPLAY 0.659574 (1685 3335);
PAINT MONO (1685 3335);
DISPLAY INVISIBLE (1685 3335);
FORCEPROP 1 LAST VOLTAGE 0.0V
J 0
(1630 3232);
DISPLAY 0.340426 (1630 3232);
PAINT SKYBLUE (1630 3232);
DISPLAY INVISIBLE (1630 3232);
FORCEPROP 1 LAST HDL_POWER GND
J 0
(1675 3425);
DISPLAY 1.170213 (1675 3425);
PAINT GREEN (1675 3425);
DISPLAY INVISIBLE (1675 3425);
FORCEPROP 2 LAST ROOM ST_SATA
J 0
(1700 3350);
DISPLAY 1.361702 (1700 3350);
PAINT ORANGE (1700 3350);
DISPLAY INVISIBLE (1700 3350);
FORCEPROP 1 LAST PATH I267
J 0
(1750 3275);
DISPLAY 0.872340 (1750 3275);
PAINT AQUA (1750 3275);
DISPLAY INVISIBLE (1750 3275);
FORCEPROP 1 LAST BODY_TYPE PLUMBING
J 0
(1630 3232);
DISPLAY 0.340426 (1630 3232);
PAINT GREEN (1630 3232);
DISPLAY INVISIBLE (1630 3232);
FORCEPROP 2 LAST CDS_LIB mstr_symbols
J 0
(1675 3275);
PAINT ORANGE (1675 3275);
DISPLAY INVISIBLE (1675 3275);
FORCEPROP 2 LAST BOM_COST ST_SATA
J 0
(1700 3350);
DISPLAY 1.361702 (1700 3350);
PAINT ORANGE (1700 3350);
DISPLAY INVISIBLE (1700 3350);
FORCEPROP 1 LAST SIZE 1B
J 0
(1750 3225);
DISPLAY 1.170213 (1750 3225);
PAINT AQUA (1750 3225);
DISPLAY INVISIBLE (1750 3225);
FORCEADD OFFPAGE..1
(-3575 3800);
FORCEPROP 2 LAST $XR0 178 
J 0
(-3827 3800);
DISPLAY 0.638298 (-3827 3800);
PAINT MONO (-3827 3800);
FORCEPROP 2 LAST CDS_LIB mstr_standard
J 0
(-3575 3800);
PAINT MONO (-3575 3800);
DISPLAY INVISIBLE (-3575 3800);
FORCEPROP 1 LAST OFFPAGE TRUE
J 0
(-3250 3675);
DISPLAY 0.872340 (-3250 3675);
PAINT GREEN (-3250 3675);
DISPLAY INVISIBLE (-3250 3675);
FORCEPROP 1 LAST COMMENT_BODY TRUE
J 0
(-3450 3700);
DISPLAY 0.872340 (-3450 3700);
PAINT GREEN (-3450 3700);
DISPLAY INVISIBLE (-3450 3700);
FORCEPROP 2 LAST PATH I268
J 0
(-3525 3875);
DISPLAY 1.021277 (-3525 3875);
PAINT ORANGE (-3525 3875);
DISPLAY INVISIBLE (-3525 3875);
FORCEADD OFFPAGE..4
(0 3900);
FORCEPROP 2 LAST $XR0 178 
J 0
(186 3900);
DISPLAY 0.638298 (186 3900);
PAINT MONO (186 3900);
FORCEPROP 2 LAST CDS_LIB mstr_standard
J 0
(0 3900);
PAINT MONO (0 3900);
DISPLAY INVISIBLE (0 3900);
FORCEPROP 1 LAST OFFPAGE TRUE
J 0
(325 3775);
DISPLAY 0.872340 (325 3775);
PAINT GREEN (325 3775);
DISPLAY INVISIBLE (325 3775);
FORCEPROP 1 LAST COMMENT_BODY TRUE
J 0
(-25 3800);
DISPLAY 0.872340 (-25 3800);
PAINT GREEN (-25 3800);
DISPLAY INVISIBLE (-25 3800);
FORCEPROP 2 LAST PATH I269
J 0
(175 3975);
DISPLAY 1.021277 (175 3975);
PAINT ORANGE (175 3975);
DISPLAY INVISIBLE (175 3975);
FORCEADD OFFPAGE..4
(0 3850);
FORCEPROP 2 LAST $XR0 178 
J 0
(186 3850);
DISPLAY 0.638298 (186 3850);
PAINT MONO (186 3850);
FORCEPROP 2 LAST CDS_LIB mstr_standard
J 0
(0 3850);
PAINT MONO (0 3850);
DISPLAY INVISIBLE (0 3850);
FORCEPROP 1 LAST OFFPAGE TRUE
J 0
(325 3725);
DISPLAY 0.872340 (325 3725);
PAINT GREEN (325 3725);
DISPLAY INVISIBLE (325 3725);
FORCEPROP 1 LAST COMMENT_BODY TRUE
J 0
(-25 3750);
DISPLAY 0.872340 (-25 3750);
PAINT GREEN (-25 3750);
DISPLAY INVISIBLE (-25 3750);
FORCEPROP 2 LAST PATH I270
J 0
(175 3925);
DISPLAY 1.021277 (175 3925);
PAINT ORANGE (175 3925);
DISPLAY INVISIBLE (175 3925);
FORCEADD TAP..6
(-5250 4050);
FORCEPROP 3 LASTPIN (-5200 4050) SIG_NAME SATA6G_PCH_PCIE_UP_SATA_RXN<1>
J 0
(-5190 4060);
DISPLAY 0.659574 (-5190 4060);
PAINT MONO (-5190 4060);
DISPLAY INVISIBLE (-5190 4060);
FORCEPROP 1 LASTPIN (-5200 4050) BN 1
J 0
(-5252 4058);
DISPLAY 0.617021 (-5252 4058);
PAINT GREEN (-5252 4058);
FORCEPROP 1 LAST PATH I271
J 0
(-5252 4050);
DISPLAY 0.872340 (-5252 4050);
PAINT GREEN (-5252 4050);
DISPLAY INVISIBLE (-5252 4050);
FORCEPROP 2 LAST CDS_LIB mstr_standard
J 0
(-5250 4050);
PAINT ORANGE (-5250 4050);
DISPLAY INVISIBLE (-5250 4050);
FORCEPROP 1 LAST BODY_TYPE PLUMBING
J 0
(-5250 4000);
DISPLAY 0.872340 (-5250 4000);
PAINT GREEN (-5250 4000);
DISPLAY INVISIBLE (-5250 4000);
FORCEPROP 1 LAST HDL_TAP TRUE
J 0
(-4925 3925);
DISPLAY 0.872340 (-4925 3925);
PAINT ORANGE (-4925 3925);
DISPLAY INVISIBLE (-4925 3925);
FORCEADD CAD_NOTE..1
(-4950 1175);
FORCEPROP 0 LAST L1 PLACE COMPONENTS CLOSE TO CONNECTOR
J 0
(-5100 1050);
DISPLAY 0.829787 (-5100 1050);
PAINT WHITE (-5100 1050);
FORCEPROP 2 LAST ROOM ST_SATA
J 0
(-5100 1075);
DISPLAY 1.361702 (-5100 1075);
PAINT ORANGE (-5100 1075);
DISPLAY INVISIBLE (-5100 1075);
FORCEPROP 1 LAST COMMENT_BODY TRUE
J 0
(-4925 1275);
DISPLAY 1.319149 (-4925 1275);
PAINT ORANGE (-4925 1275);
DISPLAY INVISIBLE (-4925 1275);
FORCEPROP 2 LAST CDS_LIB mstr_symbols
J 0
(-4950 1175);
PAINT ORANGE (-4950 1175);
DISPLAY INVISIBLE (-4950 1175);
FORCEPROP 2 LAST BOM_COST ST_SATA
J 0
(-5100 1075);
DISPLAY 1.361702 (-5100 1075);
PAINT ORANGE (-5100 1075);
DISPLAY INVISIBLE (-5100 1075);
FORCEADD DESIGN_NOTE..1
(-2175 5175);
FORCEPROP 0 LAST L1 MINI-SAS CONN SATA
J 0
(-2300 5050);
DISPLAY 0.829787 (-2300 5050);
PAINT WHITE (-2300 5050);
FORCEPROP 2 LAST ROOM ST_SATA
J 0
(-2300 5000);
DISPLAY 1.361702 (-2300 5000);
PAINT ORANGE (-2300 5000);
DISPLAY INVISIBLE (-2300 5000);
FORCEPROP 2 LAST CDS_LIB mstr_symbols
J 0
(-2175 5175);
PAINT MONO (-2175 5175);
DISPLAY INVISIBLE (-2175 5175);
FORCEPROP 2 LAST BOM_COST ST_SATA
J 0
(-2300 5000);
DISPLAY 1.361702 (-2300 5000);
PAINT ORANGE (-2300 5000);
DISPLAY INVISIBLE (-2300 5000);
FORCEPROP 1 LAST COMMENT_BODY TRUE
J 0
(-2150 5275);
DISPLAY 1.319149 (-2150 5275);
PAINT ORANGE (-2150 5275);
DISPLAY INVISIBLE (-2150 5275);
FORCEADD CAD_NOTE..1
(600 4975);
FORCEPROP 0 LAST L1 PLACE CAPS CLOSE TO PCH
J 0
(450 4850);
DISPLAY 0.829787 (450 4850);
PAINT WHITE (450 4850);
FORCEPROP 2 LAST ROOM ST_SATA
J 0
(450 4900);
DISPLAY 1.361702 (450 4900);
PAINT ORANGE (450 4900);
DISPLAY INVISIBLE (450 4900);
FORCEPROP 1 LAST COMMENT_BODY TRUE
J 0
(625 5075);
DISPLAY 1.319149 (625 5075);
PAINT ORANGE (625 5075);
DISPLAY INVISIBLE (625 5075);
FORCEPROP 2 LAST BOM_COST ST_SATA
J 0
(450 4900);
DISPLAY 1.361702 (450 4900);
PAINT ORANGE (450 4900);
DISPLAY INVISIBLE (450 4900);
FORCEPROP 2 LAST CDS_LIB mstr_symbols
J 0
(600 4975);
PAINT ORANGE (600 4975);
DISPLAY INVISIBLE (600 4975);
FORCEADD CAD_NOTE..1
(525 1225);
FORCEPROP 0 LAST L1 PLACE CAPS CLOSE TO PCH
J 0
(375 1100);
DISPLAY 0.829787 (375 1100);
PAINT WHITE (375 1100);
FORCEPROP 2 LAST BOM_COST ST_SATA
J 0
(375 1150);
DISPLAY 1.361702 (375 1150);
PAINT ORANGE (375 1150);
DISPLAY INVISIBLE (375 1150);
FORCEPROP 2 LAST CDS_LIB mstr_symbols
J 0
(525 1225);
PAINT ORANGE (525 1225);
DISPLAY INVISIBLE (525 1225);
FORCEPROP 1 LAST COMMENT_BODY TRUE
J 0
(550 1325);
DISPLAY 1.319149 (550 1325);
PAINT ORANGE (550 1325);
DISPLAY INVISIBLE (550 1325);
FORCEPROP 2 LAST ROOM ST_SATA
J 0
(375 1150);
DISPLAY 1.361702 (375 1150);
PAINT ORANGE (375 1150);
DISPLAY INVISIBLE (375 1150);
FORCEADD CAD_NOTE..1
(-4950 4900);
FORCEPROP 0 LAST L1 PLACE COMPONENTS CLOSE TO CONNECTOR
J 0
(-5100 4775);
DISPLAY 0.829787 (-5100 4775);
PAINT WHITE (-5100 4775);
FORCEPROP 2 LAST ROOM ST_SATA
J 0
(-5100 4800);
DISPLAY 1.361702 (-5100 4800);
PAINT ORANGE (-5100 4800);
DISPLAY INVISIBLE (-5100 4800);
FORCEPROP 2 LAST BOM_COST ST_SATA
J 0
(-5100 4800);
DISPLAY 1.361702 (-5100 4800);
PAINT ORANGE (-5100 4800);
DISPLAY INVISIBLE (-5100 4800);
FORCEPROP 2 LAST CDS_LIB mstr_symbols
J 0
(-4950 4900);
PAINT ORANGE (-4950 4900);
DISPLAY INVISIBLE (-4950 4900);
FORCEPROP 1 LAST COMMENT_BODY TRUE
J 0
(-4925 5000);
DISPLAY 1.319149 (-4925 5000);
PAINT ORANGE (-4925 5000);
DISPLAY INVISIBLE (-4925 5000);
FORCEADD INTEL_CORP_BPAGE..1
(2125 525);
FORCEPROP 1 LAST CDS_CON_LAST_MODIFIED Tue Dec 01 11:52:13 2015
J 0
(700 850);
PAINT ORANGE (700 850);
DISPLAY INVISIBLE (700 850);
FORCEPROP 1 LAST CUSTOM_TXT_CDS <CURRENT_DESIGN_SHEET> OF <TOTAL_DESIGN_SHEETS>
J 0
(1625 550);
PAINT GREEN (1625 550);
FORCEPROP 1 LAST CUSTOM_TXT_CDS <CON_LAST_MODIFIED>
J 0
(200 875);
PAINT GREEN (200 875);
FORCEPROP 2 LAST CUSTOM_TXT_CDS <XR_PAGE_TITLE>
J 0
(-5765 5775);
DISPLAY 0.638298 (-5765 5775);
PAINT PINK (-5765 5775);
DISPLAY INVISIBLE (-5765 5775);
FORCEPROP 1 LAST SCH_ADDRESS3 Santa Clara, CA 95052-8119
J 0
(-1850 550);
DISPLAY 0.617021 (-1850 550);
PAINT GREEN (-1850 550);
FORCEPROP 1 LAST SCH_ADDRESS2 P.O. BOX 58119
J 0
(-1850 600);
DISPLAY 0.617021 (-1850 600);
PAINT GREEN (-1850 600);
FORCEPROP 1 LAST SCH_ADDRESS1 2200 Mission College Blvd.
J 0
(-1850 650);
DISPLAY 0.617021 (-1850 650);
PAINT GREEN (-1850 650);
FORCEPROP 1 LAST SCH_TITLE MINI_SAS (1/2)
J 0
(-5825 575);
DISPLAY 1.212766 (-5825 575);
PAINT ORANGE (-5825 575);
FORCEPROP 1 LAST SCH_REV 2.420
J 0
(1875 675);
DISPLAY 0.978723 (1875 675);
PAINT YELLOW (1875 675);
FORCEPROP 1 LAST SCH_DEPT BESD
J 1
(-2325 625);
DISPLAY 1.212766 (-2325 625);
PAINT YELLOW (-2325 625);
FORCEPROP 1 LAST SCH_NUMBER H4694802
J 0
(825 675);
DISPLAY 1.212766 (825 675);
PAINT YELLOW (825 675);
FORCEPROP 2 LAST CDS_LIB mstr_symbols
J 0
(2125 525);
PAINT MONO (2125 525);
DISPLAY INVISIBLE (2125 525);
FORCEPROP 2 LAST PAGE_BORDER TRUE
J 0
(-5765 5775);
DISPLAY 0.638298 (-5765 5775);
PAINT PINK (-5765 5775);
DISPLAY INVISIBLE (-5765 5775);
FORCEPROP 1 LAST COMMENT_BODY TRUE
J 0
(2137 537);
DISPLAY 0.468085 (2137 537);
PAINT GREEN (2137 537);
DISPLAY INVISIBLE (2137 537);
FORCEPROP 2 LAST CDS_XR_PAGE_TITLE CR-173 : @BASEBOARD_FAB2_LIB.BASEBOARD_FAB2(SCH_1):PAGE173
J 0
(-5765 5775);
DISPLAY 0.638298 (-5765 5775);
PAINT PINK (-5765 5775);
DISPLAY INVISIBLE (-5765 5775);
WIRE 17 -1 (1350 4550)(1350 5075);
WIRE 17 -1 (1350 4550)(1350 4200);
WIRE 17 -1 (1350 5075)(75 5075);
FORCEPROP 2 LAST SIG_NAME SATA6G_PCH_PCIE_UP_SATA_TXN<7:0>
J 0
(140 5085);
DISPLAY 0.617021 (140 5085);
PAINT ORANGE (140 5085);
WIRE 17 -1 (1350 4200)(1350 3525);
WIRE 17 -1 (1350 3525)(1350 3100);
WIRE 17 -1 (1500 3675)(1500 4350);
WIRE 17 -1 (1500 3675)(1500 3325);
WIRE 17 -1 (1500 4700)(1500 4350);
WIRE 17 -1 (1500 4700)(1500 5225);
WIRE 17 -1 (1500 2950)(1500 3325);
WIRE 17 -1 (1500 2950)(1500 2525);
WIRE 17 -1 (75 5225)(1500 5225);
FORCEPROP 2 LAST SIG_NAME SATA6G_PCH_PCIE_UP_SATA_TXP<7:0>
J 0
(140 5235);
DISPLAY 0.617021 (140 5235);
PAINT ORANGE (140 5235);
WIRE 17 -1 (1350 2750)(1350 3100);
WIRE 17 -1 (1350 2750)(1350 2375);
WIRE 17 -1 (1350 2375)(1350 1925);
WIRE 17 -1 (1350 1925)(1350 1575);
WIRE 17 -1 (1500 2075)(1500 2525);
WIRE 17 -1 (1500 2075)(1500 1725);
WIRE 17 -1 (-5450 4575)(-5450 4225);
WIRE 17 -1 (-5450 4575)(-5450 5300);
WIRE 17 -1 (-5450 4225)(-5450 3725);
WIRE 17 -1 (-5450 3725)(-5450 3375);
WIRE 17 -1 (-4350 5300)(-5450 5300);
FORCEPROP 2 LAST SIG_NAME SATA6G_PCH_PCIE_UP_SATA_RXP<7:0>
J 0
(-5085 5310);
DISPLAY 0.617021 (-5085 5310);
PAINT ORANGE (-5085 5310);
WIRE 17 -1 (-5300 4425)(-5300 5150);
WIRE 17 -1 (-5300 4425)(-5300 4075);
WIRE 17 -1 (-5300 5150)(-4350 5150);
FORCEPROP 2 LAST SIG_NAME SATA6G_PCH_PCIE_UP_SATA_RXN<7:0>
J 0
(-5110 5160);
DISPLAY 0.617021 (-5110 5160);
PAINT ORANGE (-5110 5160);
WIRE 17 -1 (-5300 4075)(-5300 3575);
WIRE 17 -1 (-5300 3575)(-5300 3225);
WIRE 17 -1 (-5450 2925)(-5450 2575);
WIRE 17 -1 (-5450 2925)(-5450 3375);
WIRE 17 -1 (-5450 2575)(-5450 2075);
WIRE 17 -1 (-5450 2075)(-5450 1725);
WIRE 17 -1 (-5300 2775)(-5300 2425);
WIRE 17 -1 (-5300 2775)(-5300 3225);
WIRE 17 -1 (-5300 2425)(-5300 1875);
WIRE 17 -1 (-5300 1875)(-5300 1525);
WIRE 16 -1 (-1325 4500)(-1150 4500);
WIRE 16 -1 (-1150 4500)(-1150 4250);
WIRE 16 -1 (-1325 4250)(-1150 4250);
WIRE 16 -1 (-1150 4000)(-1150 4250);
WIRE 16 -1 (-1325 4000)(-1150 4000);
WIRE 16 -1 (-1150 3800)(-1150 4000);
WIRE 16 -1 (-1325 3800)(-1150 3800);
WIRE 16 -1 (-1150 3650)(-1150 3800);
WIRE 16 -1 (-1325 3650)(-1150 3650);
WIRE 16 -1 (-1150 3400)(-1150 3650);
WIRE 16 -1 (-1325 3400)(-1150 3400);
WIRE 16 -1 (-1150 3400)(-1150 3150);
WIRE 16 -1 (-1325 3150)(-1150 3150);
WIRE 16 -1 (-1150 3150)(-1150 3000);
WIRE 16 -1 (-1325 3000)(-1150 3000);
WIRE 16 -1 (-1150 3000)(-1150 2750);
WIRE 16 -1 (-1325 2750)(-1150 2750);
WIRE 16 -1 (-1150 2500)(-1150 2750);
WIRE 16 -1 (-1325 2500)(-1150 2500);
WIRE 16 -1 (-1150 2300)(-1150 2500);
WIRE 16 -1 (-1325 2300)(-1150 2300);
WIRE 16 -1 (-1150 2150)(-1150 2300);
WIRE 16 -1 (-1325 2150)(-1150 2150);
WIRE 16 -1 (-1150 1900)(-1150 2150);
WIRE 16 -1 (-1325 1900)(-1150 1900);
WIRE 16 -1 (-1150 1900)(-1150 1650);
WIRE 16 -1 (-1325 1650)(-1150 1650);
WIRE 16 -1 (-1150 1650)(-1150 1475);
WIRE 16 -1 (-2725 4500)(-2925 4500);
WIRE 16 -1 (-2925 4500)(-2925 4250);
WIRE 16 -1 (-2925 4250)(-2725 4250);
WIRE 16 -1 (-2925 4000)(-2925 4250);
WIRE 16 -1 (-2925 4000)(-2725 4000);
WIRE 16 -1 (-2925 3850)(-2925 4000);
WIRE 16 -1 (-2925 3850)(-2725 3850);
WIRE 16 -1 (-2925 3650)(-2925 3850);
WIRE 16 -1 (-2925 3650)(-2725 3650);
WIRE 16 -1 (-2925 3400)(-2925 3650);
WIRE 16 -1 (-2925 3400)(-2725 3400);
WIRE 16 -1 (-2925 3150)(-2925 3400);
WIRE 16 -1 (-2925 3150)(-2725 3150);
WIRE 16 -1 (-2925 3150)(-2925 3000);
WIRE 16 -1 (-2725 3000)(-2925 3000);
WIRE 16 -1 (-2925 3000)(-2925 2750);
WIRE 16 -1 (-2725 2750)(-2925 2750);
WIRE 16 -1 (-2925 2500)(-2925 2750);
WIRE 16 -1 (-2725 2500)(-2925 2500);
WIRE 16 -1 (-2925 2350)(-2925 2500);
WIRE 16 -1 (-2725 2350)(-2925 2350);
WIRE 16 -1 (-2925 2150)(-2925 2350);
WIRE 16 -1 (-2725 2150)(-2925 2150);
WIRE 16 -1 (-2925 1900)(-2925 2150);
WIRE 16 -1 (-2725 1900)(-2925 1900);
WIRE 16 -1 (-2925 1650)(-2925 1900);
WIRE 16 -1 (-2725 1650)(-2925 1650);
WIRE 16 -1 (-2925 1650)(-2925 1500);
WIRE 16 -1 (-4000 2200)(-4075 2200);
WIRE 16 -1 (-4075 2250)(-4075 2200);
WIRE 16 -1 (-3900 4775)(-3900 4975);
WIRE 16 -1 (1625 1900)(1625 1750);
WIRE 16 -1 (1675 3400)(1675 3325);
WIRE 16 -1 (-4275 3250)(-2725 3250);
WIRE 16 -1 (-4275 3200)(-4275 3250);
WIRE 16 -1 (-4800 3200)(-4275 3200);
FORCEPROP 2 LAST SIG_NAME SATA6G_P3_RX_C_DN
J 0
(-3500 3260);
DISPLAY 0.617021 (-3500 3260);
PAINT ORANGE (-3500 3260);
FORCEPROP 2 LASTPROP $XRERR UNIQUE?
J 0
(-3740 3260);
DISPLAY 0.638298 (-3740 3260);
PAINT MONO (-3740 3260);
DISPLAY INVISIBLE (-3740 3260);
WIRE 16 273 (425 1325)(425 4825);
WIRE 16 273 (425 1325)(1200 1325);
WIRE 16 273 (1200 4825)(425 4825);
WIRE 16 273 (1200 1325)(1200 4825);
WIRE 16 -1 (-525 1550)(950 1550);
WIRE 16 -1 (-525 1550)(-525 1750);
WIRE 16 -1 (-1325 1750)(-525 1750);
FORCEPROP 2 LAST SIG_NAME SATA6G_P7_TX_C_DN
J 0
(-1085 1760);
DISPLAY 0.617021 (-1085 1760);
PAINT ORANGE (-1085 1760);
FORCEPROP 2 LASTPROP $XRERR UNIQUE?
J 0
(-1325 1760);
DISPLAY 0.638298 (-1325 1760);
PAINT MONO (-1325 1760);
DISPLAY INVISIBLE (-1325 1760);
WIRE 16 -1 (-425 4525)(925 4525);
WIRE 16 -1 (-425 4525)(-425 4350);
WIRE 16 -1 (-1325 4350)(-425 4350);
FORCEPROP 2 LAST SIG_NAME SATA6G_P0_TX_C_DN
J 0
(-1085 4360);
DISPLAY 0.617021 (-1085 4360);
PAINT ORANGE (-1085 4360);
FORCEPROP 2 LASTPROP $XRERR UNIQUE?
J 0
(-1325 4360);
DISPLAY 0.638298 (-1325 4360);
PAINT MONO (-1325 4360);
DISPLAY INVISIBLE (-1325 4360);
WIRE 16 -1 (-1325 3750)(1675 3750);
FORCEPROP 2 LAST SIG_NAME PD_SATA0_CONTROLLER_TYPE_R
J 0
(-1085 3760);
DISPLAY 0.617021 (-1085 3760);
PAINT ORANGE (-1085 3760);
FORCEPROP 2 LASTPROP $XRERR UNIQUE?
J 0
(-1325 3760);
DISPLAY 0.638298 (-1325 3760);
PAINT MONO (-1325 3760);
DISPLAY INVISIBLE (-1325 3760);
WIRE 16 -1 (1675 3750)(1675 3600);
WIRE 16 -1 (-500 3650)(525 3650);
WIRE 16 -1 (-500 3650)(-500 3550);
WIRE 16 -1 (-1325 3550)(-500 3550);
FORCEPROP 2 LAST SIG_NAME SATA6G_P2_TX_C_DP
J 0
(-1085 3560);
DISPLAY 0.617021 (-1085 3560);
PAINT ORANGE (-1085 3560);
FORCEPROP 2 LASTPROP $XRERR UNIQUE?
J 0
(-1325 3560);
DISPLAY 0.638298 (-1325 3560);
PAINT MONO (-1325 3560);
DISPLAY INVISIBLE (-1325 3560);
WIRE 16 -1 (-1325 4150)(-225 4150);
FORCEPROP 2 LAST SIG_NAME SATA6G_P1_TX_C_DP
J 0
(-1085 4160);
DISPLAY 0.617021 (-1085 4160);
PAINT ORANGE (-1085 4160);
FORCEPROP 2 LASTPROP $XRERR UNIQUE?
J 0
(-1325 4160);
DISPLAY 0.638298 (-1325 4160);
PAINT MONO (-1325 4160);
DISPLAY INVISIBLE (-1325 4160);
WIRE 16 -1 (-225 4325)(-225 4150);
WIRE 16 -1 (-225 4325)(550 4325);
WIRE 16 -1 (-4475 2050)(-2725 2050);
FORCEPROP 2 LAST SIG_NAME SATA6G_P6_RX_C_DP
J 0
(-3500 2060);
DISPLAY 0.617021 (-3500 2060);
PAINT ORANGE (-3500 2060);
FORCEPROP 2 LASTPROP $XRERR UNIQUE?
J 0
(-3740 2060);
DISPLAY 0.638298 (-3740 2060);
PAINT MONO (-3740 2060);
DISPLAY INVISIBLE (-3740 2060);
WIRE 16 273 (-4375 4725)(-5150 4725);
WIRE 16 273 (-4375 4725)(-4375 1275);
WIRE 16 273 (-5150 4725)(-5150 1275);
WIRE 16 273 (-5150 1275)(-4375 1275);
WIRE 16 -1 (-5000 3550)(-5200 3550);
WIRE 16 -1 (-4875 1850)(-4125 1850);
WIRE 16 -1 (-4125 1850)(-4125 2000);
WIRE 16 -1 (-2725 2000)(-4125 2000);
FORCEPROP 2 LAST SIG_NAME SATA6G_P6_RX_C_DN
J 0
(-3500 2010);
DISPLAY 0.617021 (-3500 2010);
PAINT ORANGE (-3500 2010);
FORCEPROP 2 LASTPROP $XRERR UNIQUE?
J 0
(-3740 2010);
DISPLAY 0.638298 (-3740 2010);
PAINT MONO (-3740 2010);
DISPLAY INVISIBLE (-3740 2010);
WIRE 16 -1 (-4700 2900)(-5350 2900);
WIRE 16 -1 (-2725 1750)(-3825 1750);
FORCEPROP 2 LAST SIG_NAME SATA6G_P7_RX_C_DN
J 0
(-3500 1760);
DISPLAY 0.617021 (-3500 1760);
PAINT ORANGE (-3500 1760);
FORCEPROP 2 LASTPROP $XRERR UNIQUE?
J 0
(-3740 1760);
DISPLAY 0.638298 (-3740 1760);
PAINT MONO (-3740 1760);
DISPLAY INVISIBLE (-3740 1760);
WIRE 16 -1 (-3825 1500)(-3825 1750);
WIRE 16 -1 (-4875 1500)(-3825 1500);
WIRE 16 -1 (-2725 1800)(-4000 1800);
FORCEPROP 2 LAST SIG_NAME SATA6G_P7_RX_C_DP
J 0
(-3500 1810);
DISPLAY 0.617021 (-3500 1810);
PAINT ORANGE (-3500 1810);
FORCEPROP 2 LASTPROP $XRERR UNIQUE?
J 0
(-3740 1810);
DISPLAY 0.638298 (-3740 1810);
PAINT MONO (-3740 1810);
DISPLAY INVISIBLE (-3740 1810);
WIRE 16 -1 (-4000 1700)(-4000 1800);
WIRE 16 -1 (-4475 1700)(-4000 1700);
WIRE 16 -1 (-425 1700)(550 1700);
WIRE 16 -1 (-425 1700)(-425 1800);
FORCEPROP 2 LAST SIG_NAME SATA6G_P7_TX_C_DP
J 0
(-1085 1810);
DISPLAY 0.617021 (-1085 1810);
PAINT ORANGE (-1085 1810);
FORCEPROP 2 LASTPROP $XRERR UNIQUE?
J 0
(-1325 1810);
DISPLAY 0.638298 (-1325 1810);
PAINT MONO (-1325 1810);
DISPLAY INVISIBLE (-1325 1810);
WIRE 16 -1 (-425 1800)(-1325 1800);
WIRE 16 -1 (725 3650)(1400 3650);
WIRE 16 -1 (-1325 4100)(-175 4100);
FORCEPROP 2 LAST SIG_NAME SATA6G_P1_TX_C_DN
J 0
(-1085 4110);
DISPLAY 0.617021 (-1085 4110);
PAINT ORANGE (-1085 4110);
FORCEPROP 2 LASTPROP $XRERR UNIQUE?
J 0
(-1325 4110);
DISPLAY 0.638298 (-1325 4110);
PAINT MONO (-1325 4110);
DISPLAY INVISIBLE (-1325 4110);
WIRE 16 -1 (-175 4175)(-175 4100);
WIRE 16 -1 (925 4175)(-175 4175);
WIRE 16 -1 (-1325 4400)(-475 4400);
FORCEPROP 2 LAST SIG_NAME SATA6G_P0_TX_C_DP
J 0
(-1085 4410);
DISPLAY 0.617021 (-1085 4410);
PAINT ORANGE (-1085 4410);
FORCEPROP 2 LASTPROP $XRERR UNIQUE?
J 0
(-1325 4410);
DISPLAY 0.638298 (-1325 4410);
PAINT MONO (-1325 4410);
DISPLAY INVISIBLE (-1325 4410);
WIRE 16 -1 (-475 4675)(-475 4400);
WIRE 16 -1 (-475 4675)(550 4675);
WIRE 16 -1 (750 2500)(1400 2500);
WIRE 16 -1 (-250 2500)(550 2500);
WIRE 16 -1 (-250 2500)(-250 2650);
FORCEPROP 0 LAST SIG_NAME SATA6G_P5_TX_C_DP
J 0
(-1085 2660);
DISPLAY 0.617021 (-1085 2660);
PAINT ORANGE (-1085 2660);
FORCEPROP 2 LASTPROP $XRERR UNIQUE?
J 0
(-1325 2660);
DISPLAY 0.638298 (-1325 2660);
PAINT MONO (-1325 2660);
DISPLAY INVISIBLE (-1325 2660);
WIRE 16 -1 (-250 2650)(-1325 2650);
WIRE 16 -1 (750 1700)(1400 1700);
WIRE 16 -1 (-1325 2600)(-400 2600);
FORCEPROP 2 LAST SIG_NAME SATA6G_P5_TX_C_DN
J 0
(-1085 2610);
DISPLAY 0.617021 (-1085 2610);
PAINT ORANGE (-1085 2610);
FORCEPROP 2 LASTPROP $XRERR UNIQUE?
J 0
(-1325 2610);
DISPLAY 0.638298 (-1325 2610);
PAINT MONO (-1325 2610);
DISPLAY INVISIBLE (-1325 2610);
WIRE 16 -1 (-400 2350)(-400 2600);
WIRE 16 -1 (-400 2350)(925 2350);
WIRE 16 -1 (-275 1900)(950 1900);
WIRE 16 -1 (-275 1900)(-275 2000);
WIRE 16 -1 (-1325 2000)(-275 2000);
FORCEPROP 2 LAST SIG_NAME SATA6G_P6_TX_C_DN
J 0
(-1085 2010);
DISPLAY 0.617021 (-1085 2010);
PAINT ORANGE (-1085 2010);
FORCEPROP 2 LASTPROP $XRERR UNIQUE?
J 0
(-1325 2010);
DISPLAY 0.638298 (-1325 2010);
PAINT MONO (-1325 2010);
DISPLAY INVISIBLE (-1325 2010);
WIRE 16 -1 (-225 3075)(925 3075);
WIRE 16 -1 (-225 3075)(-225 3250);
FORCEPROP 2 LAST SIG_NAME SATA6G_P3_TX_C_DN
J 0
(-1085 3260);
DISPLAY 0.617021 (-1085 3260);
PAINT ORANGE (-1085 3260);
FORCEPROP 2 LASTPROP $XRERR UNIQUE?
J 0
(-1325 3260);
DISPLAY 0.638298 (-1325 3260);
PAINT MONO (-1325 3260);
DISPLAY INVISIBLE (-1325 3260);
WIRE 16 -1 (-225 3250)(-1325 3250);
WIRE 16 -1 (-1325 3300)(525 3300);
FORCEPROP 2 LAST SIG_NAME SATA6G_P3_TX_C_DP
J 0
(-1085 3310);
DISPLAY 0.617021 (-1085 3310);
PAINT ORANGE (-1085 3310);
FORCEPROP 2 LASTPROP $XRERR UNIQUE?
J 0
(-1325 3310);
DISPLAY 0.638298 (-1325 3310);
PAINT MONO (-1325 3310);
DISPLAY INVISIBLE (-1325 3310);
WIRE 16 -1 (1625 2250)(1625 2100);
WIRE 16 -1 (-1325 2250)(1625 2250);
FORCEPROP 2 LAST SIG_NAME PD_SATA1_CONTROLLER_TYPE_R
J 0
(-1085 2260);
DISPLAY 0.617021 (-1085 2260);
PAINT ORANGE (-1085 2260);
FORCEPROP 2 LASTPROP $XRERR UNIQUE?
J 0
(-1325 2260);
DISPLAY 0.638298 (-1325 2260);
PAINT MONO (-1325 2260);
DISPLAY INVISIBLE (-1325 2260);
WIRE 16 -1 (-4675 1700)(-5350 1700);
WIRE 16 -1 (-5200 1500)(-5075 1500);
WIRE 16 -1 (-5075 1850)(-5200 1850);
WIRE 16 -1 (-4675 2050)(-5350 2050);
WIRE 16 -1 (-5050 2750)(-5200 2750);
WIRE 16 -1 (-4675 3700)(-5350 3700);
WIRE 16 -1 (-5200 3200)(-5000 3200);
WIRE 16 -1 (-4675 3350)(-5350 3350);
WIRE 16 -1 (-5200 2400)(-5050 2400);
WIRE 16 -1 (-4675 2550)(-5350 2550);
WIRE 16 -1 (-5200 4050)(-4950 4050);
WIRE 16 -1 (-4850 2750)(-4150 2750);
WIRE 16 -1 (-4150 2750)(-4150 2850);
WIRE 16 -1 (-2725 2850)(-4150 2850);
FORCEPROP 2 LAST SIG_NAME SATA6G_P4_RX_C_DN
J 0
(-3500 2860);
DISPLAY 0.617021 (-3500 2860);
PAINT ORANGE (-3500 2860);
FORCEPROP 2 LASTPROP $XRERR UNIQUE?
J 0
(-3740 2860);
DISPLAY 0.638298 (-3740 2860);
PAINT MONO (-3740 2860);
DISPLAY INVISIBLE (-3740 2860);
WIRE 16 -1 (-4275 3350)(-4275 3300);
WIRE 16 -1 (-4275 3350)(-4475 3350);
WIRE 16 -1 (-2725 3300)(-4275 3300);
FORCEPROP 2 LAST SIG_NAME SATA6G_P3_RX_C_DP
J 0
(-3500 3310);
DISPLAY 0.617021 (-3500 3310);
PAINT ORANGE (-3500 3310);
FORCEPROP 2 LASTPROP $XRERR UNIQUE?
J 0
(-3740 3310);
DISPLAY 0.638298 (-3740 3310);
PAINT MONO (-3740 3310);
DISPLAY INVISIBLE (-3740 3310);
WIRE 16 -1 (-4800 3550)(-4250 3550);
WIRE 16 -1 (-4250 3550)(-4250 3500);
WIRE 16 -1 (-2725 3500)(-4250 3500);
FORCEPROP 2 LAST SIG_NAME SATA6G_P2_RX_C_DN
J 0
(-3500 3510);
DISPLAY 0.617021 (-3500 3510);
PAINT ORANGE (-3500 3510);
FORCEPROP 2 LASTPROP $XRERR UNIQUE?
J 0
(-3740 3510);
DISPLAY 0.638298 (-3740 3510);
PAINT MONO (-3740 3510);
DISPLAY INVISIBLE (-3740 3510);
WIRE 16 -1 (-4475 3700)(-4100 3700);
WIRE 16 -1 (-4100 3700)(-4100 3550);
WIRE 16 -1 (-2725 3550)(-4100 3550);
FORCEPROP 2 LAST SIG_NAME SATA6G_P2_RX_C_DP
J 0
(-3500 3560);
DISPLAY 0.617021 (-3500 3560);
PAINT ORANGE (-3500 3560);
FORCEPROP 2 LASTPROP $XRERR UNIQUE?
J 0
(-3740 3560);
DISPLAY 0.638298 (-3740 3560);
PAINT MONO (-3740 3560);
DISPLAY INVISIBLE (-3740 3560);
WIRE 16 -1 (-4225 4100)(-2725 4100);
WIRE 16 -1 (-4225 4050)(-4225 4100);
WIRE 16 -1 (-4750 4050)(-4225 4050);
FORCEPROP 2 LAST SIG_NAME SATA6G_P1_RX_C_DN
J 0
(-3500 4110);
DISPLAY 0.617021 (-3500 4110);
PAINT ORANGE (-3500 4110);
FORCEPROP 2 LASTPROP $XRERR UNIQUE?
J 0
(-3740 4110);
DISPLAY 0.638298 (-3740 4110);
PAINT MONO (-3740 4110);
DISPLAY INVISIBLE (-3740 4110);
WIRE 16 -1 (-4950 4400)(-5200 4400);
WIRE 16 -1 (-4675 4550)(-5350 4550);
WIRE 16 -1 (-4675 4200)(-5350 4200);
WIRE 16 -1 (-4475 4200)(-4225 4200);
WIRE 16 -1 (-4225 4200)(-4225 4150);
WIRE 16 -1 (-2725 4150)(-4225 4150);
FORCEPROP 2 LAST SIG_NAME SATA6G_P1_RX_C_DP
J 0
(-3500 4160);
DISPLAY 0.617021 (-3500 4160);
PAINT ORANGE (-3500 4160);
FORCEPROP 2 LASTPROP $XRERR UNIQUE?
J 0
(-3740 4160);
DISPLAY 0.638298 (-3740 4160);
PAINT MONO (-3740 4160);
DISPLAY INVISIBLE (-3740 4160);
WIRE 16 -1 (-4500 2900)(-2725 2900);
FORCEPROP 2 LAST SIG_NAME SATA6G_P4_RX_C_DP
J 0
(-3500 2910);
DISPLAY 0.617021 (-3500 2910);
PAINT ORANGE (-3500 2910);
FORCEPROP 2 LASTPROP $XRERR UNIQUE?
J 0
(-3740 2910);
DISPLAY 0.638298 (-3740 2910);
PAINT MONO (-3740 2910);
DISPLAY INVISIBLE (-3740 2910);
WIRE 16 -1 (-4475 2550)(-4050 2550);
WIRE 16 -1 (-4050 2550)(-4050 2650);
WIRE 16 -1 (-2725 2650)(-4050 2650);
FORCEPROP 2 LAST SIG_NAME SATA6G_P5_RX_C_DP
J 0
(-3500 2660);
DISPLAY 0.617021 (-3500 2660);
PAINT ORANGE (-3500 2660);
FORCEPROP 2 LASTPROP $XRERR UNIQUE?
J 0
(-3740 2660);
DISPLAY 0.638298 (-3740 2660);
PAINT MONO (-3740 2660);
DISPLAY INVISIBLE (-3740 2660);
WIRE 16 -1 (-4850 2400)(-3925 2400);
WIRE 16 -1 (-3925 2400)(-3925 2600);
WIRE 16 -1 (-2725 2600)(-3925 2600);
FORCEPROP 2 LAST SIG_NAME SATA6G_P5_RX_C_DN
J 0
(-3500 2610);
DISPLAY 0.617021 (-3500 2610);
PAINT ORANGE (-3500 2610);
FORCEPROP 2 LASTPROP $XRERR UNIQUE?
J 0
(-3740 2610);
DISPLAY 0.638298 (-3740 2610);
PAINT MONO (-3740 2610);
DISPLAY INVISIBLE (-3740 2610);
WIRE 16 -1 (-2725 2250)(-3550 2250);
FORCEPROP 2 LAST SIG_NAME PU_DATAIN1_SATA_1_R
J 0
(-3500 2260);
DISPLAY 0.617021 (-3500 2260);
PAINT ORANGE (-3500 2260);
FORCEPROP 2 LASTPROP $XRERR UNIQUE?
J 0
(-3740 2260);
DISPLAY 0.638298 (-3740 2260);
PAINT MONO (-3740 2260);
DISPLAY INVISIBLE (-3740 2260);
WIRE 16 -1 (-3550 2250)(-3550 2200);
WIRE 16 -1 (-3550 2200)(-3800 2200);
WIRE 16 -1 (-3525 3900)(-2725 3900);
FORCEPROP 2 LAST SIG_NAME TP_FM_QAT_CBL_PRSNT0_R_N
J 0
(-3500 3910);
DISPLAY 0.617021 (-3500 3910);
PAINT ORANGE (-3500 3910);
FORCEPROP 2 LASTPROP $XRERR UNIQUE?
J 0
(-3765 3900);
DISPLAY 0.638298 (-3765 3900);
PAINT MONO (-3765 3900);
DISPLAY INVISIBLE (-3765 3900);
WIRE 16 -1 (-2725 2400)(-3575 2400);
FORCEPROP 2 LAST SIG_NAME TP_FM_QAT_CBL_PRSNT1_N_R
J 0
(-3500 2410);
DISPLAY 0.617021 (-3500 2410);
PAINT ORANGE (-3500 2410);
FORCEPROP 2 LASTPROP $XRERR UNIQUE?
J 0
(-3815 2400);
DISPLAY 0.638298 (-3815 2400);
PAINT MONO (-3815 2400);
DISPLAY INVISIBLE (-3815 2400);
WIRE 16 -1 (-2725 2300)(-3575 2300);
FORCEPROP 2 LAST SIG_NAME TP_SGPIO_SATA_DATA1_R
J 0
(-3500 2310);
DISPLAY 0.617021 (-3500 2310);
PAINT ORANGE (-3500 2310);
FORCEPROP 2 LASTPROP $XRERR UNIQUE?
J 0
(-3815 2300);
DISPLAY 0.638298 (-3815 2300);
PAINT MONO (-3815 2300);
DISPLAY INVISIBLE (-3815 2300);
WIRE 16 -1 (-3525 3800)(-2725 3800);
FORCEPROP 2 LAST SIG_NAME SGPIO_PCH_SATA_DOUT0_R
J 0
(-3500 3810);
DISPLAY 0.617021 (-3500 3810);
PAINT ORANGE (-3500 3810);
WIRE 16 -1 (-475 2400)(-1325 2400);
FORCEPROP 2 LAST SIG_NAME TP_SGPIO_SATA_CLOCK1_R
J 0
(-1085 2410);
DISPLAY 0.617021 (-1085 2410);
PAINT ORANGE (-1085 2410);
FORCEPROP 2 LASTPROP $XRERR UNIQUE?
J 0
(-445 2400);
DISPLAY 0.638298 (-445 2400);
PAINT MONO (-445 2400);
DISPLAY INVISIBLE (-445 2400);
WIRE 16 -1 (-475 2350)(-1325 2350);
FORCEPROP 2 LAST SIG_NAME TP_SGPIO_SATA_LOAD1_R
J 0
(-1085 2360);
DISPLAY 0.617021 (-1085 2360);
PAINT ORANGE (-1085 2360);
FORCEPROP 2 LASTPROP $XRERR UNIQUE?
J 0
(-445 2350);
DISPLAY 0.638298 (-445 2350);
PAINT MONO (-445 2350);
DISPLAY INVISIBLE (-445 2350);
WIRE 16 -1 (-1325 3850)(-50 3850);
FORCEPROP 2 LAST SIG_NAME SGPIO_PCH_SATA_LOAD_R
J 0
(-1085 3860);
DISPLAY 0.617021 (-1085 3860);
PAINT ORANGE (-1085 3860);
WIRE 16 -1 (-1325 3900)(-50 3900);
FORCEPROP 2 LAST SIG_NAME SGPIO_PCH_SATA_CLOCK_R
J 0
(-1085 3910);
DISPLAY 0.617021 (-1085 3910);
PAINT ORANGE (-1085 3910);
WIRE 16 -1 (-250 2725)(925 2725);
WIRE 16 -1 (-250 2725)(-250 2850);
WIRE 16 -1 (-1325 2850)(-250 2850);
FORCEPROP 2 LAST SIG_NAME SATA6G_P4_TX_C_DN
J 0
(-1085 2860);
DISPLAY 0.617021 (-1085 2860);
PAINT ORANGE (-1085 2860);
FORCEPROP 2 LASTPROP $XRERR UNIQUE?
J 0
(-1325 2860);
DISPLAY 0.638298 (-1325 2860);
PAINT MONO (-1325 2860);
DISPLAY INVISIBLE (-1325 2860);
WIRE 16 -1 (-3900 4575)(-3900 3750);
WIRE 16 -1 (-3900 3750)(-2725 3750);
FORCEPROP 2 LAST SIG_NAME PU_DATAIN1_SATA_0_R
J 0
(-3500 3750);
DISPLAY 0.617021 (-3500 3750);
PAINT ORANGE (-3500 3750);
FORCEPROP 2 LASTPROP $XRERR UNIQUE?
J 0
(-3740 3750);
DISPLAY 0.638298 (-3740 3750);
PAINT MONO (-3740 3750);
DISPLAY INVISIBLE (-3740 3750);
WIRE 16 -1 (-4750 4400)(-4075 4400);
WIRE 16 -1 (-4075 4400)(-4075 4350);
WIRE 16 -1 (-2725 4350)(-4075 4350);
FORCEPROP 2 LAST SIG_NAME SATA6G_P0_RX_C_DN
J 0
(-3500 4360);
DISPLAY 0.617021 (-3500 4360);
PAINT ORANGE (-3500 4360);
FORCEPROP 2 LASTPROP $XRERR UNIQUE?
J 0
(-3740 4360);
DISPLAY 0.638298 (-3740 4360);
PAINT MONO (-3740 4360);
DISPLAY INVISIBLE (-3740 4360);
WIRE 16 -1 (-4475 4550)(-3975 4550);
WIRE 16 -1 (-3975 4550)(-3975 4400);
WIRE 16 -1 (-2725 4400)(-3975 4400);
FORCEPROP 2 LAST SIG_NAME SATA6G_P0_RX_C_DP
J 0
(-3500 4400);
DISPLAY 0.617021 (-3500 4400);
PAINT ORANGE (-3500 4400);
FORCEPROP 2 LASTPROP $XRERR UNIQUE?
J 0
(-3740 4400);
DISPLAY 0.638298 (-3740 4400);
PAINT MONO (-3740 4400);
DISPLAY INVISIBLE (-3740 4400);
WIRE 16 -1 (-1325 2050)(550 2050);
FORCEPROP 2 LAST SIG_NAME SATA6G_P6_TX_C_DP
J 0
(-1085 2060);
DISPLAY 0.617021 (-1085 2060);
PAINT ORANGE (-1085 2060);
FORCEPROP 2 LASTPROP $XRERR UNIQUE?
J 0
(-1325 2060);
DISPLAY 0.638298 (-1325 2060);
PAINT MONO (-1325 2060);
DISPLAY INVISIBLE (-1325 2060);
WIRE 16 -1 (-1325 2925)(550 2925);
FORCEPROP 0 LAST SIG_NAME SATA6G_P4_TX_C_DP
J 0
(-1085 2935);
DISPLAY 0.617021 (-1085 2935);
PAINT ORANGE (-1085 2935);
FORCEPROP 2 LASTPROP $XRERR UNIQUE?
J 0
(-1325 2935);
DISPLAY 0.638298 (-1325 2935);
PAINT MONO (-1325 2935);
DISPLAY INVISIBLE (-1325 2935);
WIRE 16 -1 (-1325 2925)(-1325 2900);
WIRE 16 -1 (-1325 3500)(900 3500);
FORCEPROP 2 LAST SIG_NAME SATA6G_P2_TX_C_DN
J 0
(-1085 3510);
DISPLAY 0.617021 (-1085 3510);
PAINT ORANGE (-1085 3510);
FORCEPROP 2 LASTPROP $XRERR UNIQUE?
J 0
(-1325 3510);
DISPLAY 0.638298 (-1325 3510);
PAINT MONO (-1325 3510);
DISPLAY INVISIBLE (-1325 3510);
WIRE 16 -1 (1150 1550)(1250 1550);
WIRE 16 -1 (1150 1900)(1250 1900);
WIRE 16 -1 (750 2050)(1400 2050);
WIRE 16 -1 (750 2925)(1400 2925);
WIRE 16 -1 (725 3300)(1400 3300);
WIRE 16 -1 (1125 2350)(1250 2350);
WIRE 16 -1 (1125 2725)(1250 2725);
WIRE 16 -1 (1125 3075)(1250 3075);
WIRE 16 -1 (1100 3500)(1250 3500);
WIRE 16 -1 (750 4675)(1400 4675);
WIRE 16 -1 (750 4325)(1400 4325);
WIRE 16 -1 (1125 4175)(1250 4175);
WIRE 16 -1 (1125 4525)(1250 4525);
DOT 1 (-2925 2500);
DOT 1 (-2925 1650);
DOT 1 (-1150 1650);
DOT 1 (-2925 1900);
DOT 1 (-1150 1900);
DOT 1 (-2925 2150);
DOT 1 (-1150 2150);
DOT 1 (-1150 2300);
DOT 1 (-2925 2350);
DOT 1 (-1150 2500);
DOT 1 (-2925 2750);
DOT 1 (-1150 2750);
DOT 1 (-2925 3000);
DOT 1 (-1150 3000);
DOT 1 (-2925 3150);
DOT 1 (-1150 3150);
DOT 1 (-2925 3400);
DOT 1 (-1150 3400);
DOT 1 (-2925 3650);
DOT 1 (-1150 3650);
DOT 1 (-2925 3850);
DOT 1 (-2925 4000);
DOT 1 (-1150 4000);
DOT 1 (-2925 4250);
DOT 1 (-1150 4250);
DOT 1 (-1150 3800);
FORCENOTE
VERTICAL MINI-SAS
(-2300 4900) 0;
DISPLAY LEFT (-2300 4900);
DISPLAY 1.021277 (-2300 4900);
PAINT PURPLE (-2300 4900);
FORCENOTE
BOM_COST=ST_SATA
(-5825 700) 0;
DISPLAY LEFT (-5825 700);
DISPLAY 2.148936 (-5825 700);
PAINT PURPLE (-5825 700);
FORCENOTE
ROOM=ST_SATA
(-5825 825) 0;
DISPLAY LEFT (-5825 825);
DISPLAY 2.148936 (-5825 825);
PAINT PURPLE (-5825 825);
QUIT
